FILE_TYPE = MACRO_DRAWING;
SET COLOR_WIRE YELLOW;
SET COLOR_PROP ORANGE;
SET COLOR_DOT WHITE;
SET COLOR_ARC YELLOW;
SET COLOR_BODY GREEN;
SET COLOR_NOTE PURPLE;
SET PROP_DISPLAY VALUE;
SET PAGE_NUMBER P164;
FORCEADD OFFPAGE..1
(-2500 1800);
FORCEPROP 2 LAST $XR0 29 
J 0
(-2751 1800);
DISPLAY 0.638298 (-2751 1800);
PAINT MONO (-2751 1800);
FORCEPROP 2 LAST CDS_LIB standard
J 0
(-2500 1800);
DISPLAY INVISIBLE (-2500 1800);
FORCEPROP 1 LAST OFFPAGE TRUE
J 0
(-2175 1675);
DISPLAY 0.872340 (-2175 1675);
DISPLAY INVISIBLE (-2175 1675);
FORCEPROP 1 LAST COMMENT_BODY TRUE
J 0
(-2375 1700);
DISPLAY 0.872340 (-2375 1700);
PAINT GREEN (-2375 1700);
DISPLAY INVISIBLE (-2375 1700);
FORCEPROP 2 LAST PATH I1
J 0
(-2775 1850);
DISPLAY 1.021277 (-2775 1850);
DISPLAY INVISIBLE (-2775 1850);
FORCEADD TAP..1
R 2
(-1550 925);
FORCEPROP 3 LASTPIN (-1500 925) SIG_NAME P5E_CPU0_PE0_TX_DP<3>
J 0
(-1490 935);
DISPLAY 0.659574 (-1490 935);
PAINT MONO (-1490 935);
DISPLAY INVISIBLE (-1490 935);
FORCEPROP 1 LASTPIN (-1500 925) BN 3
J 2
(-1488 933);
DISPLAY 0.680851 (-1488 933);
PAINT GREEN (-1488 933);
FORCEPROP 2 LAST CDS_LIB standard
J 0
(-1550 925);
DISPLAY INVISIBLE (-1550 925);
FORCEPROP 1 LAST BODY_TYPE PLUMBING
J 2
(-1550 975);
DISPLAY 0.872340 (-1550 975);
PAINT GREEN (-1550 975);
DISPLAY INVISIBLE (-1550 975);
FORCEPROP 1 LAST HDL_TAP TRUE
J 2
(-1875 800);
DISPLAY 0.872340 (-1875 800);
DISPLAY INVISIBLE (-1875 800);
FORCEPROP 1 LAST PATH I10
J 2
(-1548 925);
DISPLAY 0.872340 (-1548 925);
PAINT GREEN (-1548 925);
DISPLAY INVISIBLE (-1548 925);
FORCEADD TAP..1
(175 2700);
FORCEPROP 3 LASTPIN (125 2700) SIG_NAME P5E_CPU0_PE0_TX_C_DP<10>
J 0
(135 2710);
DISPLAY 0.659574 (135 2710);
PAINT MONO (135 2710);
DISPLAY INVISIBLE (135 2710);
FORCEPROP 1 LASTPIN (125 2700) BN 10
J 0
(113 2708);
DISPLAY 0.680851 (113 2708);
PAINT GREEN (113 2708);
FORCEPROP 2 LAST CDS_LIB standard
J 0
(175 2700);
DISPLAY INVISIBLE (175 2700);
FORCEPROP 1 LAST BODY_TYPE PLUMBING
J 0
(175 2750);
DISPLAY 0.872340 (175 2750);
PAINT GREEN (175 2750);
DISPLAY INVISIBLE (175 2750);
FORCEPROP 1 LAST HDL_TAP TRUE
J 0
(500 2575);
DISPLAY 0.872340 (500 2575);
DISPLAY INVISIBLE (500 2575);
FORCEPROP 1 LAST PATH I100
J 0
(173 2700);
DISPLAY 0.872340 (173 2700);
PAINT GREEN (173 2700);
DISPLAY INVISIBLE (173 2700);
FORCEADD TAP..1
(175 3100);
FORCEPROP 3 LASTPIN (125 3100) SIG_NAME P5E_CPU0_PE0_TX_C_DP<12>
J 0
(135 3110);
DISPLAY 0.659574 (135 3110);
PAINT MONO (135 3110);
DISPLAY INVISIBLE (135 3110);
FORCEPROP 1 LASTPIN (125 3100) BN 12
J 0
(113 3108);
DISPLAY 0.680851 (113 3108);
PAINT GREEN (113 3108);
FORCEPROP 2 LAST CDS_LIB standard
J 0
(175 3100);
DISPLAY INVISIBLE (175 3100);
FORCEPROP 1 LAST BODY_TYPE PLUMBING
J 0
(175 3150);
DISPLAY 0.872340 (175 3150);
PAINT GREEN (175 3150);
DISPLAY INVISIBLE (175 3150);
FORCEPROP 1 LAST HDL_TAP TRUE
J 0
(500 2975);
DISPLAY 0.872340 (500 2975);
DISPLAY INVISIBLE (500 2975);
FORCEPROP 1 LAST PATH I101
J 0
(173 3100);
DISPLAY 0.872340 (173 3100);
PAINT GREEN (173 3100);
DISPLAY INVISIBLE (173 3100);
FORCEADD TAP..1
(175 3300);
FORCEPROP 3 LASTPIN (125 3300) SIG_NAME P5E_CPU0_PE0_TX_C_DP<13>
J 0
(135 3310);
DISPLAY 0.659574 (135 3310);
PAINT MONO (135 3310);
DISPLAY INVISIBLE (135 3310);
FORCEPROP 1 LASTPIN (125 3300) BN 13
J 0
(113 3308);
DISPLAY 0.680851 (113 3308);
PAINT GREEN (113 3308);
FORCEPROP 2 LAST CDS_LIB standard
J 0
(175 3300);
DISPLAY INVISIBLE (175 3300);
FORCEPROP 1 LAST BODY_TYPE PLUMBING
J 0
(175 3350);
DISPLAY 0.872340 (175 3350);
PAINT GREEN (175 3350);
DISPLAY INVISIBLE (175 3350);
FORCEPROP 1 LAST HDL_TAP TRUE
J 0
(500 3175);
DISPLAY 0.872340 (500 3175);
DISPLAY INVISIBLE (500 3175);
FORCEPROP 1 LAST PATH I102
J 0
(173 3300);
DISPLAY 0.872340 (173 3300);
PAINT GREEN (173 3300);
DISPLAY INVISIBLE (173 3300);
FORCEADD TAP..1
(175 3500);
FORCEPROP 3 LASTPIN (125 3500) SIG_NAME P5E_CPU0_PE0_TX_C_DP<14>
J 0
(135 3510);
DISPLAY 0.659574 (135 3510);
PAINT MONO (135 3510);
DISPLAY INVISIBLE (135 3510);
FORCEPROP 1 LASTPIN (125 3500) BN 14
J 0
(113 3508);
DISPLAY 0.680851 (113 3508);
PAINT GREEN (113 3508);
FORCEPROP 2 LAST CDS_LIB standard
J 0
(175 3500);
DISPLAY INVISIBLE (175 3500);
FORCEPROP 1 LAST BODY_TYPE PLUMBING
J 0
(175 3550);
DISPLAY 0.872340 (175 3550);
PAINT GREEN (175 3550);
DISPLAY INVISIBLE (175 3550);
FORCEPROP 1 LAST HDL_TAP TRUE
J 0
(500 3375);
DISPLAY 0.872340 (500 3375);
DISPLAY INVISIBLE (500 3375);
FORCEPROP 1 LAST PATH I103
J 0
(173 3500);
DISPLAY 0.872340 (173 3500);
PAINT GREEN (173 3500);
DISPLAY INVISIBLE (173 3500);
FORCEADD TAP..1
(175 3700);
FORCEPROP 3 LASTPIN (125 3700) SIG_NAME P5E_CPU0_PE0_TX_C_DP<15>
J 0
(135 3710);
DISPLAY 0.659574 (135 3710);
PAINT MONO (135 3710);
DISPLAY INVISIBLE (135 3710);
FORCEPROP 1 LASTPIN (125 3700) BN 15
J 0
(113 3708);
DISPLAY 0.680851 (113 3708);
PAINT GREEN (113 3708);
FORCEPROP 2 LAST CDS_LIB standard
J 0
(175 3700);
DISPLAY INVISIBLE (175 3700);
FORCEPROP 1 LAST BODY_TYPE PLUMBING
J 0
(175 3750);
DISPLAY 0.872340 (175 3750);
PAINT GREEN (175 3750);
DISPLAY INVISIBLE (175 3750);
FORCEPROP 1 LAST HDL_TAP TRUE
J 0
(500 3575);
DISPLAY 0.872340 (500 3575);
DISPLAY INVISIBLE (500 3575);
FORCEPROP 1 LAST PATH I104
J 0
(173 3700);
DISPLAY 0.872340 (173 3700);
PAINT GREEN (173 3700);
DISPLAY INVISIBLE (173 3700);
FORCEADD OFFPAGE..2
(1175 3725);
FORCEPROP 2 LAST $XR0 139 
J 0
(1364 3725);
DISPLAY 0.638298 (1364 3725);
PAINT MONO (1364 3725);
FORCEPROP 2 LAST CDS_LIB standard
J 0
(1175 3725);
DISPLAY INVISIBLE (1175 3725);
FORCEPROP 1 LAST OFFPAGE TRUE
J 0
(1500 3600);
DISPLAY 0.872340 (1500 3600);
DISPLAY INVISIBLE (1500 3600);
FORCEPROP 1 LAST COMMENT_BODY TRUE
J 0
(1130 3630);
DISPLAY 0.872340 (1130 3630);
PAINT GREEN (1130 3630);
DISPLAY INVISIBLE (1130 3630);
FORCEPROP 2 LAST PATH I105
J 0
(1375 3775);
DISPLAY 1.021277 (1375 3775);
DISPLAY INVISIBLE (1375 3775);
FORCEADD OFFPAGE..2
(1175 3775);
FORCEPROP 2 LAST $XR0 139 
J 0
(1364 3775);
DISPLAY 0.638298 (1364 3775);
PAINT MONO (1364 3775);
FORCEPROP 2 LAST CDS_LIB standard
J 0
(1175 3775);
DISPLAY INVISIBLE (1175 3775);
FORCEPROP 1 LAST OFFPAGE TRUE
J 0
(1500 3650);
DISPLAY 0.872340 (1500 3650);
DISPLAY INVISIBLE (1500 3650);
FORCEPROP 1 LAST COMMENT_BODY TRUE
J 0
(1130 3680);
DISPLAY 0.872340 (1130 3680);
PAINT GREEN (1130 3680);
DISPLAY INVISIBLE (1130 3680);
FORCEPROP 2 LAST PATH I106
J 0
(1375 3825);
DISPLAY 1.021277 (1375 3825);
DISPLAY INVISIBLE (1375 3825);
FORCEADD OFFPAGE..1
(2050 3725);
FORCEPROP 2 LAST $XR0 30 
J 0
(1829 3725);
DISPLAY 0.638298 (1829 3725);
PAINT MONO (1829 3725);
FORCEPROP 2 LAST CDS_LIB standard
J 0
(2050 3725);
DISPLAY INVISIBLE (2050 3725);
FORCEPROP 1 LAST OFFPAGE TRUE
J 0
(2375 3600);
DISPLAY 0.872340 (2375 3600);
DISPLAY INVISIBLE (2375 3600);
FORCEPROP 1 LAST COMMENT_BODY TRUE
J 0
(2175 3625);
DISPLAY 0.872340 (2175 3625);
PAINT GREEN (2175 3625);
DISPLAY INVISIBLE (2175 3625);
FORCEPROP 2 LAST PATH I107
J 0
(1800 3775);
DISPLAY 1.021277 (1800 3775);
DISPLAY INVISIBLE (1800 3775);
FORCEADD OFFPAGE..1
(2050 3775);
FORCEPROP 2 LAST $XR0 30 
J 0
(1829 3775);
DISPLAY 0.638298 (1829 3775);
PAINT MONO (1829 3775);
FORCEPROP 2 LAST CDS_LIB standard
J 0
(2050 3775);
DISPLAY INVISIBLE (2050 3775);
FORCEPROP 1 LAST OFFPAGE TRUE
J 0
(2375 3650);
DISPLAY 0.872340 (2375 3650);
DISPLAY INVISIBLE (2375 3650);
FORCEPROP 1 LAST COMMENT_BODY TRUE
J 0
(2175 3675);
DISPLAY 0.872340 (2175 3675);
PAINT GREEN (2175 3675);
DISPLAY INVISIBLE (2175 3675);
FORCEPROP 2 LAST PATH I108
J 0
(1800 3825);
DISPLAY 1.021277 (1800 3825);
DISPLAY INVISIBLE (1800 3825);
FORCEADD TAP..1
R 2
(3000 525);
FORCEPROP 3 LASTPIN (3050 525) SIG_NAME P5E_CPU0_PE2_TX_DP<1>
J 0
(3060 535);
DISPLAY 0.659574 (3060 535);
PAINT MONO (3060 535);
DISPLAY INVISIBLE (3060 535);
FORCEPROP 1 LASTPIN (3050 525) BN 1
J 2
(3062 533);
DISPLAY 0.680851 (3062 533);
PAINT GREEN (3062 533);
FORCEPROP 2 LAST CDS_LIB standard
J 0
(3000 525);
DISPLAY INVISIBLE (3000 525);
FORCEPROP 1 LAST BODY_TYPE PLUMBING
J 2
(3000 575);
DISPLAY 0.872340 (3000 575);
PAINT GREEN (3000 575);
DISPLAY INVISIBLE (3000 575);
FORCEPROP 1 LAST HDL_TAP TRUE
J 2
(2675 400);
DISPLAY 0.872340 (2675 400);
DISPLAY INVISIBLE (2675 400);
FORCEPROP 1 LAST PATH I109
J 2
(3002 525);
DISPLAY 0.872340 (3002 525);
PAINT GREEN (3002 525);
DISPLAY INVISIBLE (3002 525);
FORCEADD TAP..1
R 2
(-1550 1125);
FORCEPROP 3 LASTPIN (-1500 1125) SIG_NAME P5E_CPU0_PE0_TX_DP<4>
J 0
(-1490 1135);
DISPLAY 0.659574 (-1490 1135);
PAINT MONO (-1490 1135);
DISPLAY INVISIBLE (-1490 1135);
FORCEPROP 1 LASTPIN (-1500 1125) BN 4
J 2
(-1488 1133);
DISPLAY 0.680851 (-1488 1133);
PAINT GREEN (-1488 1133);
FORCEPROP 2 LAST CDS_LIB standard
J 0
(-1550 1125);
DISPLAY INVISIBLE (-1550 1125);
FORCEPROP 1 LAST BODY_TYPE PLUMBING
J 2
(-1550 1175);
DISPLAY 0.872340 (-1550 1175);
PAINT GREEN (-1550 1175);
DISPLAY INVISIBLE (-1550 1175);
FORCEPROP 1 LAST HDL_TAP TRUE
J 2
(-1875 1000);
DISPLAY 0.872340 (-1875 1000);
DISPLAY INVISIBLE (-1875 1000);
FORCEPROP 1 LAST PATH I11
J 2
(-1548 1125);
DISPLAY 0.872340 (-1548 1125);
PAINT GREEN (-1548 1125);
DISPLAY INVISIBLE (-1548 1125);
FORCEADD TAP..1
R 2
(3000 325);
FORCEPROP 3 LASTPIN (3050 325) SIG_NAME P5E_CPU0_PE2_TX_DP<0>
J 0
(3060 335);
DISPLAY 0.659574 (3060 335);
PAINT MONO (3060 335);
DISPLAY INVISIBLE (3060 335);
FORCEPROP 1 LASTPIN (3050 325) BN 0
J 2
(3062 333);
DISPLAY 0.680851 (3062 333);
PAINT GREEN (3062 333);
FORCEPROP 2 LAST CDS_LIB standard
J 0
(3000 325);
DISPLAY INVISIBLE (3000 325);
FORCEPROP 1 LAST BODY_TYPE PLUMBING
J 2
(3000 375);
DISPLAY 0.872340 (3000 375);
PAINT GREEN (3000 375);
DISPLAY INVISIBLE (3000 375);
FORCEPROP 1 LAST HDL_TAP TRUE
J 2
(2675 200);
DISPLAY 0.872340 (2675 200);
DISPLAY INVISIBLE (2675 200);
FORCEPROP 1 LAST PATH I110
J 2
(3002 325);
DISPLAY 0.872340 (3002 325);
PAINT GREEN (3002 325);
DISPLAY INVISIBLE (3002 325);
FORCEADD TAP..1
R 2
(3000 925);
FORCEPROP 3 LASTPIN (3050 925) SIG_NAME P5E_CPU0_PE2_TX_DP<3>
J 0
(3060 935);
DISPLAY 0.659574 (3060 935);
PAINT MONO (3060 935);
DISPLAY INVISIBLE (3060 935);
FORCEPROP 1 LASTPIN (3050 925) BN 3
J 2
(3062 933);
DISPLAY 0.680851 (3062 933);
PAINT GREEN (3062 933);
FORCEPROP 2 LAST CDS_LIB standard
J 0
(3000 925);
DISPLAY INVISIBLE (3000 925);
FORCEPROP 1 LAST BODY_TYPE PLUMBING
J 2
(3000 975);
DISPLAY 0.872340 (3000 975);
PAINT GREEN (3000 975);
DISPLAY INVISIBLE (3000 975);
FORCEPROP 1 LAST HDL_TAP TRUE
J 2
(2675 800);
DISPLAY 0.872340 (2675 800);
DISPLAY INVISIBLE (2675 800);
FORCEPROP 1 LAST PATH I111
J 2
(3002 925);
DISPLAY 0.872340 (3002 925);
PAINT GREEN (3002 925);
DISPLAY INVISIBLE (3002 925);
FORCEADD TAP..1
R 2
(3000 725);
FORCEPROP 3 LASTPIN (3050 725) SIG_NAME P5E_CPU0_PE2_TX_DP<2>
J 0
(3060 735);
DISPLAY 0.659574 (3060 735);
PAINT MONO (3060 735);
DISPLAY INVISIBLE (3060 735);
FORCEPROP 1 LASTPIN (3050 725) BN 2
J 2
(3062 733);
DISPLAY 0.680851 (3062 733);
PAINT GREEN (3062 733);
FORCEPROP 2 LAST CDS_LIB standard
J 0
(3000 725);
DISPLAY INVISIBLE (3000 725);
FORCEPROP 1 LAST BODY_TYPE PLUMBING
J 2
(3000 775);
DISPLAY 0.872340 (3000 775);
PAINT GREEN (3000 775);
DISPLAY INVISIBLE (3000 775);
FORCEPROP 1 LAST HDL_TAP TRUE
J 2
(2675 600);
DISPLAY 0.872340 (2675 600);
DISPLAY INVISIBLE (2675 600);
FORCEPROP 1 LAST PATH I112
J 2
(3002 725);
DISPLAY 0.872340 (3002 725);
PAINT GREEN (3002 725);
DISPLAY INVISIBLE (3002 725);
FORCEADD TAP..1
R 2
(3000 1525);
FORCEPROP 3 LASTPIN (3050 1525) SIG_NAME P5E_CPU0_PE2_TX_DP<6>
J 0
(3060 1535);
DISPLAY 0.659574 (3060 1535);
PAINT MONO (3060 1535);
DISPLAY INVISIBLE (3060 1535);
FORCEPROP 1 LASTPIN (3050 1525) BN 6
J 2
(3062 1533);
DISPLAY 0.680851 (3062 1533);
PAINT GREEN (3062 1533);
FORCEPROP 2 LAST CDS_LIB standard
J 0
(3000 1525);
DISPLAY INVISIBLE (3000 1525);
FORCEPROP 1 LAST BODY_TYPE PLUMBING
J 2
(3000 1575);
DISPLAY 0.872340 (3000 1575);
PAINT GREEN (3000 1575);
DISPLAY INVISIBLE (3000 1575);
FORCEPROP 1 LAST HDL_TAP TRUE
J 2
(2675 1400);
DISPLAY 0.872340 (2675 1400);
DISPLAY INVISIBLE (2675 1400);
FORCEPROP 1 LAST PATH I113
J 2
(3002 1525);
DISPLAY 0.872340 (3002 1525);
PAINT GREEN (3002 1525);
DISPLAY INVISIBLE (3002 1525);
FORCEADD TAP..1
R 2
(3000 1325);
FORCEPROP 3 LASTPIN (3050 1325) SIG_NAME P5E_CPU0_PE2_TX_DP<5>
J 0
(3060 1335);
DISPLAY 0.659574 (3060 1335);
PAINT MONO (3060 1335);
DISPLAY INVISIBLE (3060 1335);
FORCEPROP 1 LASTPIN (3050 1325) BN 5
J 2
(3062 1333);
DISPLAY 0.680851 (3062 1333);
PAINT GREEN (3062 1333);
FORCEPROP 2 LAST CDS_LIB standard
J 0
(3000 1325);
DISPLAY INVISIBLE (3000 1325);
FORCEPROP 1 LAST BODY_TYPE PLUMBING
J 2
(3000 1375);
DISPLAY 0.872340 (3000 1375);
PAINT GREEN (3000 1375);
DISPLAY INVISIBLE (3000 1375);
FORCEPROP 1 LAST HDL_TAP TRUE
J 2
(2675 1200);
DISPLAY 0.872340 (2675 1200);
DISPLAY INVISIBLE (2675 1200);
FORCEPROP 1 LAST PATH I114
J 2
(3002 1325);
DISPLAY 0.872340 (3002 1325);
PAINT GREEN (3002 1325);
DISPLAY INVISIBLE (3002 1325);
FORCEADD TAP..1
R 2
(3000 1125);
FORCEPROP 3 LASTPIN (3050 1125) SIG_NAME P5E_CPU0_PE2_TX_DP<4>
J 0
(3060 1135);
DISPLAY 0.659574 (3060 1135);
PAINT MONO (3060 1135);
DISPLAY INVISIBLE (3060 1135);
FORCEPROP 1 LASTPIN (3050 1125) BN 4
J 2
(3062 1133);
DISPLAY 0.680851 (3062 1133);
PAINT GREEN (3062 1133);
FORCEPROP 2 LAST CDS_LIB standard
J 0
(3000 1125);
DISPLAY INVISIBLE (3000 1125);
FORCEPROP 1 LAST BODY_TYPE PLUMBING
J 2
(3000 1175);
DISPLAY 0.872340 (3000 1175);
PAINT GREEN (3000 1175);
DISPLAY INVISIBLE (3000 1175);
FORCEPROP 1 LAST HDL_TAP TRUE
J 2
(2675 1000);
DISPLAY 0.872340 (2675 1000);
DISPLAY INVISIBLE (2675 1000);
FORCEPROP 1 LAST PATH I115
J 2
(3002 1125);
DISPLAY 0.872340 (3002 1125);
PAINT GREEN (3002 1125);
DISPLAY INVISIBLE (3002 1125);
FORCEADD TAP..1
R 2
(3000 1725);
FORCEPROP 3 LASTPIN (3050 1725) SIG_NAME P5E_CPU0_PE2_TX_DP<7>
J 0
(3060 1735);
DISPLAY 0.659574 (3060 1735);
PAINT MONO (3060 1735);
DISPLAY INVISIBLE (3060 1735);
FORCEPROP 1 LASTPIN (3050 1725) BN 7
J 2
(3062 1733);
DISPLAY 0.680851 (3062 1733);
PAINT GREEN (3062 1733);
FORCEPROP 2 LAST CDS_LIB standard
J 0
(3000 1725);
DISPLAY INVISIBLE (3000 1725);
FORCEPROP 1 LAST BODY_TYPE PLUMBING
J 2
(3000 1775);
DISPLAY 0.872340 (3000 1775);
PAINT GREEN (3000 1775);
DISPLAY INVISIBLE (3000 1775);
FORCEPROP 1 LAST HDL_TAP TRUE
J 2
(2675 1600);
DISPLAY 0.872340 (2675 1600);
DISPLAY INVISIBLE (2675 1600);
FORCEPROP 1 LAST PATH I116
J 2
(3002 1725);
DISPLAY 0.872340 (3002 1725);
PAINT GREEN (3002 1725);
DISPLAY INVISIBLE (3002 1725);
FORCEADD TAP..1
R 2
(3250 375);
FORCEPROP 3 LASTPIN (3300 375) SIG_NAME P5E_CPU0_PE2_TX_DN<0>
J 0
(3310 385);
DISPLAY 0.659574 (3310 385);
PAINT MONO (3310 385);
DISPLAY INVISIBLE (3310 385);
FORCEPROP 1 LASTPIN (3300 375) BN 0
J 2
(3312 383);
DISPLAY 0.680851 (3312 383);
PAINT GREEN (3312 383);
FORCEPROP 2 LAST CDS_LIB standard
J 0
(3250 375);
DISPLAY INVISIBLE (3250 375);
FORCEPROP 1 LAST BODY_TYPE PLUMBING
J 2
(3250 425);
DISPLAY 0.872340 (3250 425);
PAINT GREEN (3250 425);
DISPLAY INVISIBLE (3250 425);
FORCEPROP 1 LAST HDL_TAP TRUE
J 2
(2925 250);
DISPLAY 0.872340 (2925 250);
DISPLAY INVISIBLE (2925 250);
FORCEPROP 1 LAST PATH I117
J 2
(3252 375);
DISPLAY 0.872340 (3252 375);
PAINT GREEN (3252 375);
DISPLAY INVISIBLE (3252 375);
FORCEADD TAP..1
R 2
(3250 575);
FORCEPROP 3 LASTPIN (3300 575) SIG_NAME P5E_CPU0_PE2_TX_DN<1>
J 0
(3310 585);
DISPLAY 0.659574 (3310 585);
PAINT MONO (3310 585);
DISPLAY INVISIBLE (3310 585);
FORCEPROP 1 LASTPIN (3300 575) BN 1
J 2
(3312 583);
DISPLAY 0.680851 (3312 583);
PAINT GREEN (3312 583);
FORCEPROP 2 LAST CDS_LIB standard
J 0
(3250 575);
DISPLAY INVISIBLE (3250 575);
FORCEPROP 1 LAST BODY_TYPE PLUMBING
J 2
(3250 625);
DISPLAY 0.872340 (3250 625);
PAINT GREEN (3250 625);
DISPLAY INVISIBLE (3250 625);
FORCEPROP 1 LAST HDL_TAP TRUE
J 2
(2925 450);
DISPLAY 0.872340 (2925 450);
DISPLAY INVISIBLE (2925 450);
FORCEPROP 1 LAST PATH I118
J 2
(3252 575);
DISPLAY 0.872340 (3252 575);
PAINT GREEN (3252 575);
DISPLAY INVISIBLE (3252 575);
FORCEADD TAP..1
R 2
(3250 775);
FORCEPROP 3 LASTPIN (3300 775) SIG_NAME P5E_CPU0_PE2_TX_DN<2>
J 0
(3310 785);
DISPLAY 0.659574 (3310 785);
PAINT MONO (3310 785);
DISPLAY INVISIBLE (3310 785);
FORCEPROP 1 LASTPIN (3300 775) BN 2
J 2
(3312 783);
DISPLAY 0.680851 (3312 783);
PAINT GREEN (3312 783);
FORCEPROP 2 LAST CDS_LIB standard
J 0
(3250 775);
DISPLAY INVISIBLE (3250 775);
FORCEPROP 1 LAST BODY_TYPE PLUMBING
J 2
(3250 825);
DISPLAY 0.872340 (3250 825);
PAINT GREEN (3250 825);
DISPLAY INVISIBLE (3250 825);
FORCEPROP 1 LAST HDL_TAP TRUE
J 2
(2925 650);
DISPLAY 0.872340 (2925 650);
DISPLAY INVISIBLE (2925 650);
FORCEPROP 1 LAST PATH I119
J 2
(3252 775);
DISPLAY 0.872340 (3252 775);
PAINT GREEN (3252 775);
DISPLAY INVISIBLE (3252 775);
FORCEADD TAP..1
R 2
(-1300 775);
FORCEPROP 3 LASTPIN (-1250 775) SIG_NAME P5E_CPU0_PE0_TX_DN<2>
J 0
(-1240 785);
DISPLAY 0.659574 (-1240 785);
PAINT MONO (-1240 785);
DISPLAY INVISIBLE (-1240 785);
FORCEPROP 1 LASTPIN (-1250 775) BN 2
J 2
(-1238 783);
DISPLAY 0.680851 (-1238 783);
PAINT GREEN (-1238 783);
FORCEPROP 2 LAST CDS_LIB standard
J 0
(-1300 775);
DISPLAY INVISIBLE (-1300 775);
FORCEPROP 1 LAST BODY_TYPE PLUMBING
J 2
(-1300 825);
DISPLAY 0.872340 (-1300 825);
PAINT GREEN (-1300 825);
DISPLAY INVISIBLE (-1300 825);
FORCEPROP 1 LAST HDL_TAP TRUE
J 2
(-1625 650);
DISPLAY 0.872340 (-1625 650);
DISPLAY INVISIBLE (-1625 650);
FORCEPROP 1 LAST PATH I12
J 2
(-1298 775);
DISPLAY 0.872340 (-1298 775);
PAINT GREEN (-1298 775);
DISPLAY INVISIBLE (-1298 775);
FORCEADD TAP..1
R 2
(3250 975);
FORCEPROP 3 LASTPIN (3300 975) SIG_NAME P5E_CPU0_PE2_TX_DN<3>
J 0
(3310 985);
DISPLAY 0.659574 (3310 985);
PAINT MONO (3310 985);
DISPLAY INVISIBLE (3310 985);
FORCEPROP 1 LASTPIN (3300 975) BN 3
J 2
(3312 983);
DISPLAY 0.680851 (3312 983);
PAINT GREEN (3312 983);
FORCEPROP 2 LAST CDS_LIB standard
J 0
(3250 975);
DISPLAY INVISIBLE (3250 975);
FORCEPROP 1 LAST BODY_TYPE PLUMBING
J 2
(3250 1025);
DISPLAY 0.872340 (3250 1025);
PAINT GREEN (3250 1025);
DISPLAY INVISIBLE (3250 1025);
FORCEPROP 1 LAST HDL_TAP TRUE
J 2
(2925 850);
DISPLAY 0.872340 (2925 850);
DISPLAY INVISIBLE (2925 850);
FORCEPROP 1 LAST PATH I120
J 2
(3252 975);
DISPLAY 0.872340 (3252 975);
PAINT GREEN (3252 975);
DISPLAY INVISIBLE (3252 975);
FORCEADD Q_CAP_DIFFBUS..2
R 2
(3975 325);
FORCEPROP 1 LAST PART_NUMBER SP_CH4221MEE01
J 2
(3859 413);
DISPLAY 0.574468 (3859 413);
PAINT GREEN (3859 413);
DISPLAY INVISIBLE (3859 413);
FORCEPROP 2 LAST VALUE DIFF BUS_0.22UF
J 2
(3825 325);
DISPLAY 0.553191 (3825 325);
FORCEPROP 1 LAST $LOCATION C965
J 2
(4209 342);
DISPLAY 0.723404 (4209 342);
PAINT GREEN (4209 342);
FORCEPROP 2 LASTPIN (4050 325) $PN 1
J 0
(4060 335);
DISPLAY 0.808511 (4060 335);
FORCEPROP 2 LASTPIN (3900 325) $PN 2
J 2
(3890 335);
DISPLAY 0.808511 (3890 335);
FORCEPROP 2 LAST TOLERANCE 20%
J 2
(3900 375);
DISPLAY 0.553191 (3900 375);
DISPLAY INVISIBLE (3900 375);
FORCEPROP 2 LAST PACK_TYPE C0201
J 2
(3800 375);
DISPLAY 0.553191 (3800 375);
DISPLAY INVISIBLE (3800 375);
FORCEPROP 1 LAST MATERIAL X6S
J 2
(3984 404);
DISPLAY 0.574468 (3984 404);
PAINT GREEN (3984 404);
DISPLAY INVISIBLE (3984 404);
FORCEPROP 2 LAST VOLTAGE 6.3V
J 2
(3625 375);
DISPLAY 0.553191 (3625 375);
DISPLAY INVISIBLE (3625 375);
FORCEPROP 1 LAST CDS_LMAN_SYM_OUTLINE -25,50,25,-50
J 2
(3975 325);
DISPLAY 0.468085 (3975 325);
PAINT GREEN (3975 325);
DISPLAY INVISIBLE (3975 325);
FORCEPROP 2 LAST CDS_LIB pure_quanta
J 2
(3975 325);
DISPLAY INVISIBLE (3975 325);
FORCEPROP 1 LAST PIN_NAMES_ROTATE TRUE
J 2
(3975 325);
DISPLAY 0.489362 (3975 325);
PAINT GREEN (3975 325);
DISPLAY INVISIBLE (3975 325);
FORCEPROP 1 LAST PATH I121
J 2
(3975 325);
DISPLAY 0.723404 (3975 325);
DISPLAY INVISIBLE (3975 325);
FORCEPROP 1 LAST $LOCATION C965
J 0
(4225 400);
DISPLAY 1.021277 (4225 400);
DISPLAY INVISIBLE (4225 400);
FORCEPROP 2 LAST CDS_LOCATION C965
J 0
(4225 400);
DISPLAY 1.021277 (4225 400);
DISPLAY INVISIBLE (4225 400);
FORCEPROP 2 LAST $SEC 1
J 2
(4150 400);
DISPLAY 0.680851 (4150 400);
PAINT MONO (4150 400);
DISPLAY INVISIBLE (4150 400);
FORCEPROP 2 LAST CDS_SEC 1
J 2
(4150 400);
DISPLAY 0.680851 (4150 400);
DISPLAY INVISIBLE (4150 400);
FORCEADD Q_CAP_DIFFBUS..2
R 2
(3975 375);
FORCEPROP 1 LAST PART_NUMBER SP_CH4221MEE01
J 2
(3859 463);
DISPLAY 0.574468 (3859 463);
PAINT GREEN (3859 463);
DISPLAY INVISIBLE (3859 463);
FORCEPROP 2 LAST VALUE DIFF BUS_0.22UF
J 2
(3825 375);
DISPLAY 0.553191 (3825 375);
FORCEPROP 1 LAST $LOCATION C964
J 2
(4209 392);
DISPLAY 0.723404 (4209 392);
PAINT GREEN (4209 392);
FORCEPROP 2 LASTPIN (4050 375) $PN 1
J 0
(4060 385);
DISPLAY 0.808511 (4060 385);
FORCEPROP 2 LASTPIN (3900 375) $PN 2
J 2
(3890 385);
DISPLAY 0.808511 (3890 385);
FORCEPROP 2 LAST TOLERANCE 20%
J 2
(3900 425);
DISPLAY 0.553191 (3900 425);
DISPLAY INVISIBLE (3900 425);
FORCEPROP 2 LAST PACK_TYPE C0201
J 2
(3800 425);
DISPLAY 0.553191 (3800 425);
DISPLAY INVISIBLE (3800 425);
FORCEPROP 1 LAST MATERIAL X6S
J 2
(3984 454);
DISPLAY 0.574468 (3984 454);
PAINT GREEN (3984 454);
DISPLAY INVISIBLE (3984 454);
FORCEPROP 2 LAST VOLTAGE 6.3V
J 2
(3625 425);
DISPLAY 0.553191 (3625 425);
DISPLAY INVISIBLE (3625 425);
FORCEPROP 1 LAST CDS_LMAN_SYM_OUTLINE -25,50,25,-50
J 2
(3975 375);
DISPLAY 0.468085 (3975 375);
PAINT GREEN (3975 375);
DISPLAY INVISIBLE (3975 375);
FORCEPROP 2 LAST CDS_LIB pure_quanta
J 2
(3975 375);
DISPLAY INVISIBLE (3975 375);
FORCEPROP 1 LAST PIN_NAMES_ROTATE TRUE
J 2
(3975 375);
DISPLAY 0.489362 (3975 375);
PAINT GREEN (3975 375);
DISPLAY INVISIBLE (3975 375);
FORCEPROP 1 LAST PATH I122
J 2
(3975 375);
DISPLAY 0.723404 (3975 375);
DISPLAY INVISIBLE (3975 375);
FORCEPROP 1 LAST $LOCATION C964
J 0
(4225 450);
DISPLAY 1.021277 (4225 450);
DISPLAY INVISIBLE (4225 450);
FORCEPROP 2 LAST CDS_LOCATION C964
J 0
(4225 450);
DISPLAY 1.021277 (4225 450);
DISPLAY INVISIBLE (4225 450);
FORCEPROP 2 LAST $SEC 1
J 2
(4150 450);
DISPLAY 0.680851 (4150 450);
PAINT MONO (4150 450);
DISPLAY INVISIBLE (4150 450);
FORCEPROP 2 LAST CDS_SEC 1
J 2
(4150 450);
DISPLAY 0.680851 (4150 450);
DISPLAY INVISIBLE (4150 450);
FORCEADD Q_CAP_DIFFBUS..2
R 2
(3975 525);
FORCEPROP 1 LAST PART_NUMBER SP_CH4221MEE01
J 2
(3859 613);
DISPLAY 0.574468 (3859 613);
PAINT GREEN (3859 613);
DISPLAY INVISIBLE (3859 613);
FORCEPROP 2 LAST VALUE DIFF BUS_0.22UF
J 2
(3825 525);
DISPLAY 0.553191 (3825 525);
FORCEPROP 1 LAST $LOCATION C963
J 2
(4209 542);
DISPLAY 0.723404 (4209 542);
PAINT GREEN (4209 542);
FORCEPROP 2 LASTPIN (4050 525) $PN 1
J 0
(4060 535);
DISPLAY 0.808511 (4060 535);
FORCEPROP 2 LASTPIN (3900 525) $PN 2
J 2
(3890 535);
DISPLAY 0.808511 (3890 535);
FORCEPROP 2 LAST TOLERANCE 20%
J 2
(3900 575);
DISPLAY 0.553191 (3900 575);
DISPLAY INVISIBLE (3900 575);
FORCEPROP 2 LAST PACK_TYPE C0201
J 2
(3800 575);
DISPLAY 0.553191 (3800 575);
DISPLAY INVISIBLE (3800 575);
FORCEPROP 1 LAST MATERIAL X6S
J 2
(3984 604);
DISPLAY 0.574468 (3984 604);
PAINT GREEN (3984 604);
DISPLAY INVISIBLE (3984 604);
FORCEPROP 2 LAST VOLTAGE 6.3V
J 2
(3625 575);
DISPLAY 0.553191 (3625 575);
DISPLAY INVISIBLE (3625 575);
FORCEPROP 1 LAST CDS_LMAN_SYM_OUTLINE -25,50,25,-50
J 2
(3975 525);
DISPLAY 0.468085 (3975 525);
PAINT GREEN (3975 525);
DISPLAY INVISIBLE (3975 525);
FORCEPROP 2 LAST CDS_LIB pure_quanta
J 2
(3975 525);
DISPLAY INVISIBLE (3975 525);
FORCEPROP 1 LAST PIN_NAMES_ROTATE TRUE
J 2
(3975 525);
DISPLAY 0.489362 (3975 525);
PAINT GREEN (3975 525);
DISPLAY INVISIBLE (3975 525);
FORCEPROP 1 LAST PATH I123
J 2
(3975 525);
DISPLAY 0.723404 (3975 525);
DISPLAY INVISIBLE (3975 525);
FORCEPROP 1 LAST $LOCATION C963
J 0
(4225 600);
DISPLAY 1.021277 (4225 600);
DISPLAY INVISIBLE (4225 600);
FORCEPROP 2 LAST CDS_LOCATION C963
J 0
(4225 600);
DISPLAY 1.021277 (4225 600);
DISPLAY INVISIBLE (4225 600);
FORCEPROP 2 LAST $SEC 1
J 2
(4150 600);
DISPLAY 0.680851 (4150 600);
PAINT MONO (4150 600);
DISPLAY INVISIBLE (4150 600);
FORCEPROP 2 LAST CDS_SEC 1
J 2
(4150 600);
DISPLAY 0.680851 (4150 600);
DISPLAY INVISIBLE (4150 600);
FORCEADD Q_CAP_DIFFBUS..2
R 2
(3975 575);
FORCEPROP 1 LAST PART_NUMBER SP_CH4221MEE01
J 2
(3859 663);
DISPLAY 0.574468 (3859 663);
PAINT GREEN (3859 663);
DISPLAY INVISIBLE (3859 663);
FORCEPROP 2 LAST VALUE DIFF BUS_0.22UF
J 2
(3825 575);
DISPLAY 0.553191 (3825 575);
FORCEPROP 1 LAST $LOCATION C962
J 2
(4209 592);
DISPLAY 0.723404 (4209 592);
PAINT GREEN (4209 592);
FORCEPROP 2 LASTPIN (4050 575) $PN 1
J 0
(4060 585);
DISPLAY 0.808511 (4060 585);
FORCEPROP 2 LASTPIN (3900 575) $PN 2
J 2
(3890 585);
DISPLAY 0.808511 (3890 585);
FORCEPROP 2 LAST TOLERANCE 20%
J 2
(3900 625);
DISPLAY 0.553191 (3900 625);
DISPLAY INVISIBLE (3900 625);
FORCEPROP 2 LAST PACK_TYPE C0201
J 2
(3800 625);
DISPLAY 0.553191 (3800 625);
DISPLAY INVISIBLE (3800 625);
FORCEPROP 1 LAST MATERIAL X6S
J 2
(3984 654);
DISPLAY 0.574468 (3984 654);
PAINT GREEN (3984 654);
DISPLAY INVISIBLE (3984 654);
FORCEPROP 2 LAST VOLTAGE 6.3V
J 2
(3625 625);
DISPLAY 0.553191 (3625 625);
DISPLAY INVISIBLE (3625 625);
FORCEPROP 2 LAST CDS_LIB pure_quanta
J 2
(3975 575);
DISPLAY INVISIBLE (3975 575);
FORCEPROP 1 LAST CDS_LMAN_SYM_OUTLINE -25,50,25,-50
J 2
(3975 575);
DISPLAY 0.468085 (3975 575);
PAINT GREEN (3975 575);
DISPLAY INVISIBLE (3975 575);
FORCEPROP 1 LAST PIN_NAMES_ROTATE TRUE
J 2
(3975 575);
DISPLAY 0.489362 (3975 575);
PAINT GREEN (3975 575);
DISPLAY INVISIBLE (3975 575);
FORCEPROP 1 LAST PATH I124
J 2
(3975 575);
DISPLAY 0.723404 (3975 575);
DISPLAY INVISIBLE (3975 575);
FORCEPROP 1 LAST $LOCATION C962
J 0
(4225 650);
DISPLAY 1.021277 (4225 650);
DISPLAY INVISIBLE (4225 650);
FORCEPROP 2 LAST CDS_LOCATION C962
J 0
(4225 650);
DISPLAY 1.021277 (4225 650);
DISPLAY INVISIBLE (4225 650);
FORCEPROP 2 LAST $SEC 1
J 2
(4150 650);
DISPLAY 0.680851 (4150 650);
PAINT MONO (4150 650);
DISPLAY INVISIBLE (4150 650);
FORCEPROP 2 LAST CDS_SEC 1
J 2
(4150 650);
DISPLAY 0.680851 (4150 650);
DISPLAY INVISIBLE (4150 650);
FORCEADD Q_CAP_DIFFBUS..2
R 2
(3975 725);
FORCEPROP 1 LAST PART_NUMBER SP_CH4221MEE01
J 2
(3859 813);
DISPLAY 0.574468 (3859 813);
PAINT GREEN (3859 813);
DISPLAY INVISIBLE (3859 813);
FORCEPROP 2 LAST VALUE DIFF BUS_0.22UF
J 2
(3825 725);
DISPLAY 0.553191 (3825 725);
FORCEPROP 1 LAST $LOCATION C961
J 2
(4209 742);
DISPLAY 0.723404 (4209 742);
PAINT GREEN (4209 742);
FORCEPROP 2 LASTPIN (4050 725) $PN 1
J 0
(4060 735);
DISPLAY 0.808511 (4060 735);
FORCEPROP 2 LASTPIN (3900 725) $PN 2
J 2
(3890 735);
DISPLAY 0.808511 (3890 735);
FORCEPROP 2 LAST TOLERANCE 20%
J 2
(3900 775);
DISPLAY 0.553191 (3900 775);
DISPLAY INVISIBLE (3900 775);
FORCEPROP 2 LAST PACK_TYPE C0201
J 2
(3800 775);
DISPLAY 0.553191 (3800 775);
DISPLAY INVISIBLE (3800 775);
FORCEPROP 1 LAST MATERIAL X6S
J 2
(3984 804);
DISPLAY 0.574468 (3984 804);
PAINT GREEN (3984 804);
DISPLAY INVISIBLE (3984 804);
FORCEPROP 2 LAST VOLTAGE 6.3V
J 2
(3625 775);
DISPLAY 0.553191 (3625 775);
DISPLAY INVISIBLE (3625 775);
FORCEPROP 1 LAST CDS_LMAN_SYM_OUTLINE -25,50,25,-50
J 2
(3975 725);
DISPLAY 0.468085 (3975 725);
PAINT GREEN (3975 725);
DISPLAY INVISIBLE (3975 725);
FORCEPROP 2 LAST CDS_LIB pure_quanta
J 2
(3975 725);
DISPLAY INVISIBLE (3975 725);
FORCEPROP 1 LAST PIN_NAMES_ROTATE TRUE
J 2
(3975 725);
DISPLAY 0.489362 (3975 725);
PAINT GREEN (3975 725);
DISPLAY INVISIBLE (3975 725);
FORCEPROP 1 LAST PATH I125
J 2
(3975 725);
DISPLAY 0.723404 (3975 725);
DISPLAY INVISIBLE (3975 725);
FORCEPROP 1 LAST $LOCATION C961
J 0
(4225 800);
DISPLAY 1.021277 (4225 800);
DISPLAY INVISIBLE (4225 800);
FORCEPROP 2 LAST CDS_LOCATION C961
J 0
(4225 800);
DISPLAY 1.021277 (4225 800);
DISPLAY INVISIBLE (4225 800);
FORCEPROP 2 LAST $SEC 1
J 2
(4150 800);
DISPLAY 0.680851 (4150 800);
PAINT MONO (4150 800);
DISPLAY INVISIBLE (4150 800);
FORCEPROP 2 LAST CDS_SEC 1
J 2
(4150 800);
DISPLAY 0.680851 (4150 800);
DISPLAY INVISIBLE (4150 800);
FORCEADD Q_CAP_DIFFBUS..2
R 2
(3975 775);
FORCEPROP 1 LAST PART_NUMBER SP_CH4221MEE01
J 2
(3859 863);
DISPLAY 0.574468 (3859 863);
PAINT GREEN (3859 863);
DISPLAY INVISIBLE (3859 863);
FORCEPROP 2 LAST VALUE DIFF BUS_0.22UF
J 2
(3825 775);
DISPLAY 0.553191 (3825 775);
FORCEPROP 1 LAST $LOCATION C960
J 2
(4209 792);
DISPLAY 0.723404 (4209 792);
PAINT GREEN (4209 792);
FORCEPROP 2 LASTPIN (4050 775) $PN 1
J 0
(4060 785);
DISPLAY 0.808511 (4060 785);
FORCEPROP 2 LASTPIN (3900 775) $PN 2
J 2
(3890 785);
DISPLAY 0.808511 (3890 785);
FORCEPROP 2 LAST TOLERANCE 20%
J 2
(3900 825);
DISPLAY 0.553191 (3900 825);
DISPLAY INVISIBLE (3900 825);
FORCEPROP 2 LAST PACK_TYPE C0201
J 2
(3800 825);
DISPLAY 0.553191 (3800 825);
DISPLAY INVISIBLE (3800 825);
FORCEPROP 1 LAST MATERIAL X6S
J 2
(3984 854);
DISPLAY 0.574468 (3984 854);
PAINT GREEN (3984 854);
DISPLAY INVISIBLE (3984 854);
FORCEPROP 2 LAST VOLTAGE 6.3V
J 2
(3625 825);
DISPLAY 0.553191 (3625 825);
DISPLAY INVISIBLE (3625 825);
FORCEPROP 1 LAST CDS_LMAN_SYM_OUTLINE -25,50,25,-50
J 2
(3975 775);
DISPLAY 0.468085 (3975 775);
PAINT GREEN (3975 775);
DISPLAY INVISIBLE (3975 775);
FORCEPROP 2 LAST CDS_LIB pure_quanta
J 2
(3975 775);
DISPLAY INVISIBLE (3975 775);
FORCEPROP 1 LAST PIN_NAMES_ROTATE TRUE
J 2
(3975 775);
DISPLAY 0.489362 (3975 775);
PAINT GREEN (3975 775);
DISPLAY INVISIBLE (3975 775);
FORCEPROP 1 LAST PATH I126
J 2
(3975 775);
DISPLAY 0.723404 (3975 775);
DISPLAY INVISIBLE (3975 775);
FORCEPROP 1 LAST $LOCATION C960
J 0
(4225 850);
DISPLAY 1.021277 (4225 850);
DISPLAY INVISIBLE (4225 850);
FORCEPROP 2 LAST CDS_LOCATION C960
J 0
(4225 850);
DISPLAY 1.021277 (4225 850);
DISPLAY INVISIBLE (4225 850);
FORCEPROP 2 LAST $SEC 1
J 2
(4150 850);
DISPLAY 0.680851 (4150 850);
PAINT MONO (4150 850);
DISPLAY INVISIBLE (4150 850);
FORCEPROP 2 LAST CDS_SEC 1
J 2
(4150 850);
DISPLAY 0.680851 (4150 850);
DISPLAY INVISIBLE (4150 850);
FORCEADD Q_CAP_DIFFBUS..2
R 2
(3975 925);
FORCEPROP 1 LAST PART_NUMBER SP_CH4221MEE01
J 2
(3859 1013);
DISPLAY 0.574468 (3859 1013);
PAINT GREEN (3859 1013);
DISPLAY INVISIBLE (3859 1013);
FORCEPROP 2 LAST VALUE DIFF BUS_0.22UF
J 2
(3825 925);
DISPLAY 0.553191 (3825 925);
FORCEPROP 1 LAST $LOCATION C959
J 2
(4209 942);
DISPLAY 0.723404 (4209 942);
PAINT GREEN (4209 942);
FORCEPROP 2 LASTPIN (4050 925) $PN 1
J 0
(4060 935);
DISPLAY 0.808511 (4060 935);
FORCEPROP 2 LASTPIN (3900 925) $PN 2
J 2
(3890 935);
DISPLAY 0.808511 (3890 935);
FORCEPROP 2 LAST TOLERANCE 20%
J 2
(3900 975);
DISPLAY 0.553191 (3900 975);
DISPLAY INVISIBLE (3900 975);
FORCEPROP 2 LAST PACK_TYPE C0201
J 2
(3800 975);
DISPLAY 0.553191 (3800 975);
DISPLAY INVISIBLE (3800 975);
FORCEPROP 1 LAST MATERIAL X6S
J 2
(3984 1004);
DISPLAY 0.574468 (3984 1004);
PAINT GREEN (3984 1004);
DISPLAY INVISIBLE (3984 1004);
FORCEPROP 2 LAST VOLTAGE 6.3V
J 2
(3625 975);
DISPLAY 0.553191 (3625 975);
DISPLAY INVISIBLE (3625 975);
FORCEPROP 2 LAST CDS_LIB pure_quanta
J 2
(3975 925);
DISPLAY INVISIBLE (3975 925);
FORCEPROP 1 LAST CDS_LMAN_SYM_OUTLINE -25,50,25,-50
J 2
(3975 925);
DISPLAY 0.468085 (3975 925);
PAINT GREEN (3975 925);
DISPLAY INVISIBLE (3975 925);
FORCEPROP 1 LAST PIN_NAMES_ROTATE TRUE
J 2
(3975 925);
DISPLAY 0.489362 (3975 925);
PAINT GREEN (3975 925);
DISPLAY INVISIBLE (3975 925);
FORCEPROP 1 LAST PATH I127
J 2
(3975 925);
DISPLAY 0.723404 (3975 925);
DISPLAY INVISIBLE (3975 925);
FORCEPROP 1 LAST $LOCATION C959
J 0
(4225 1000);
DISPLAY 1.021277 (4225 1000);
DISPLAY INVISIBLE (4225 1000);
FORCEPROP 2 LAST CDS_LOCATION C959
J 0
(4225 1000);
DISPLAY 1.021277 (4225 1000);
DISPLAY INVISIBLE (4225 1000);
FORCEPROP 2 LAST $SEC 1
J 2
(4150 1000);
DISPLAY 0.680851 (4150 1000);
PAINT MONO (4150 1000);
DISPLAY INVISIBLE (4150 1000);
FORCEPROP 2 LAST CDS_SEC 1
J 2
(4150 1000);
DISPLAY 0.680851 (4150 1000);
DISPLAY INVISIBLE (4150 1000);
FORCEADD Q_CAP_DIFFBUS..2
R 2
(3975 975);
FORCEPROP 1 LAST PART_NUMBER SP_CH4221MEE01
J 2
(3859 1063);
DISPLAY 0.574468 (3859 1063);
PAINT GREEN (3859 1063);
DISPLAY INVISIBLE (3859 1063);
FORCEPROP 2 LAST VALUE DIFF BUS_0.22UF
J 2
(3825 975);
DISPLAY 0.553191 (3825 975);
FORCEPROP 1 LAST $LOCATION C958
J 2
(4209 992);
DISPLAY 0.723404 (4209 992);
PAINT GREEN (4209 992);
FORCEPROP 2 LASTPIN (4050 975) $PN 1
J 0
(4060 985);
DISPLAY 0.808511 (4060 985);
FORCEPROP 2 LASTPIN (3900 975) $PN 2
J 2
(3890 985);
DISPLAY 0.808511 (3890 985);
FORCEPROP 2 LAST TOLERANCE 20%
J 2
(3900 1025);
DISPLAY 0.553191 (3900 1025);
DISPLAY INVISIBLE (3900 1025);
FORCEPROP 2 LAST PACK_TYPE C0201
J 2
(3800 1025);
DISPLAY 0.553191 (3800 1025);
DISPLAY INVISIBLE (3800 1025);
FORCEPROP 1 LAST MATERIAL X6S
J 2
(3984 1054);
DISPLAY 0.574468 (3984 1054);
PAINT GREEN (3984 1054);
DISPLAY INVISIBLE (3984 1054);
FORCEPROP 2 LAST VOLTAGE 6.3V
J 2
(3625 1025);
DISPLAY 0.553191 (3625 1025);
DISPLAY INVISIBLE (3625 1025);
FORCEPROP 2 LAST CDS_LIB pure_quanta
J 2
(3975 975);
DISPLAY INVISIBLE (3975 975);
FORCEPROP 1 LAST CDS_LMAN_SYM_OUTLINE -25,50,25,-50
J 2
(3975 975);
DISPLAY 0.468085 (3975 975);
PAINT GREEN (3975 975);
DISPLAY INVISIBLE (3975 975);
FORCEPROP 1 LAST PIN_NAMES_ROTATE TRUE
J 2
(3975 975);
DISPLAY 0.489362 (3975 975);
PAINT GREEN (3975 975);
DISPLAY INVISIBLE (3975 975);
FORCEPROP 1 LAST PATH I128
J 2
(3975 975);
DISPLAY 0.723404 (3975 975);
DISPLAY INVISIBLE (3975 975);
FORCEPROP 1 LAST $LOCATION C958
J 0
(4225 1050);
DISPLAY 1.021277 (4225 1050);
DISPLAY INVISIBLE (4225 1050);
FORCEPROP 2 LAST CDS_LOCATION C958
J 0
(4225 1050);
DISPLAY 1.021277 (4225 1050);
DISPLAY INVISIBLE (4225 1050);
FORCEPROP 2 LAST $SEC 1
J 2
(4150 1050);
DISPLAY 0.680851 (4150 1050);
PAINT MONO (4150 1050);
DISPLAY INVISIBLE (4150 1050);
FORCEPROP 2 LAST CDS_SEC 1
J 2
(4150 1050);
DISPLAY 0.680851 (4150 1050);
DISPLAY INVISIBLE (4150 1050);
FORCEADD TAP..1
R 2
(3250 1375);
FORCEPROP 3 LASTPIN (3300 1375) SIG_NAME P5E_CPU0_PE2_TX_DN<5>
J 0
(3310 1385);
DISPLAY 0.659574 (3310 1385);
PAINT MONO (3310 1385);
DISPLAY INVISIBLE (3310 1385);
FORCEPROP 1 LASTPIN (3300 1375) BN 5
J 2
(3312 1383);
DISPLAY 0.680851 (3312 1383);
PAINT GREEN (3312 1383);
FORCEPROP 2 LAST CDS_LIB standard
J 0
(3250 1375);
DISPLAY INVISIBLE (3250 1375);
FORCEPROP 1 LAST BODY_TYPE PLUMBING
J 2
(3250 1425);
DISPLAY 0.872340 (3250 1425);
PAINT GREEN (3250 1425);
DISPLAY INVISIBLE (3250 1425);
FORCEPROP 1 LAST HDL_TAP TRUE
J 2
(2925 1250);
DISPLAY 0.872340 (2925 1250);
DISPLAY INVISIBLE (2925 1250);
FORCEPROP 1 LAST PATH I129
J 2
(3252 1375);
DISPLAY 0.872340 (3252 1375);
PAINT GREEN (3252 1375);
DISPLAY INVISIBLE (3252 1375);
FORCEADD TAP..1
R 2
(-1300 975);
FORCEPROP 3 LASTPIN (-1250 975) SIG_NAME P5E_CPU0_PE0_TX_DN<3>
J 0
(-1240 985);
DISPLAY 0.659574 (-1240 985);
PAINT MONO (-1240 985);
DISPLAY INVISIBLE (-1240 985);
FORCEPROP 1 LASTPIN (-1250 975) BN 3
J 2
(-1238 983);
DISPLAY 0.680851 (-1238 983);
PAINT GREEN (-1238 983);
FORCEPROP 2 LAST CDS_LIB standard
J 0
(-1300 975);
DISPLAY INVISIBLE (-1300 975);
FORCEPROP 1 LAST BODY_TYPE PLUMBING
J 2
(-1300 1025);
DISPLAY 0.872340 (-1300 1025);
PAINT GREEN (-1300 1025);
DISPLAY INVISIBLE (-1300 1025);
FORCEPROP 1 LAST HDL_TAP TRUE
J 2
(-1625 850);
DISPLAY 0.872340 (-1625 850);
DISPLAY INVISIBLE (-1625 850);
FORCEPROP 1 LAST PATH I13
J 2
(-1298 975);
DISPLAY 0.872340 (-1298 975);
PAINT GREEN (-1298 975);
DISPLAY INVISIBLE (-1298 975);
FORCEADD TAP..1
R 2
(3250 1175);
FORCEPROP 3 LASTPIN (3300 1175) SIG_NAME P5E_CPU0_PE2_TX_DN<4>
J 0
(3310 1185);
DISPLAY 0.659574 (3310 1185);
PAINT MONO (3310 1185);
DISPLAY INVISIBLE (3310 1185);
FORCEPROP 1 LASTPIN (3300 1175) BN 4
J 2
(3312 1183);
DISPLAY 0.680851 (3312 1183);
PAINT GREEN (3312 1183);
FORCEPROP 2 LAST CDS_LIB standard
J 0
(3250 1175);
DISPLAY INVISIBLE (3250 1175);
FORCEPROP 1 LAST BODY_TYPE PLUMBING
J 2
(3250 1225);
DISPLAY 0.872340 (3250 1225);
PAINT GREEN (3250 1225);
DISPLAY INVISIBLE (3250 1225);
FORCEPROP 1 LAST HDL_TAP TRUE
J 2
(2925 1050);
DISPLAY 0.872340 (2925 1050);
DISPLAY INVISIBLE (2925 1050);
FORCEPROP 1 LAST PATH I130
J 2
(3252 1175);
DISPLAY 0.872340 (3252 1175);
PAINT GREEN (3252 1175);
DISPLAY INVISIBLE (3252 1175);
FORCEADD TAP..1
R 2
(3250 1575);
FORCEPROP 3 LASTPIN (3300 1575) SIG_NAME P5E_CPU0_PE2_TX_DN<6>
J 0
(3310 1585);
DISPLAY 0.659574 (3310 1585);
PAINT MONO (3310 1585);
DISPLAY INVISIBLE (3310 1585);
FORCEPROP 1 LASTPIN (3300 1575) BN 6
J 2
(3312 1583);
DISPLAY 0.680851 (3312 1583);
PAINT GREEN (3312 1583);
FORCEPROP 2 LAST CDS_LIB standard
J 0
(3250 1575);
DISPLAY INVISIBLE (3250 1575);
FORCEPROP 1 LAST BODY_TYPE PLUMBING
J 2
(3250 1625);
DISPLAY 0.872340 (3250 1625);
PAINT GREEN (3250 1625);
DISPLAY INVISIBLE (3250 1625);
FORCEPROP 1 LAST HDL_TAP TRUE
J 2
(2925 1450);
DISPLAY 0.872340 (2925 1450);
DISPLAY INVISIBLE (2925 1450);
FORCEPROP 1 LAST PATH I131
J 2
(3252 1575);
DISPLAY 0.872340 (3252 1575);
PAINT GREEN (3252 1575);
DISPLAY INVISIBLE (3252 1575);
FORCEADD TAP..1
R 2
(3250 1775);
FORCEPROP 3 LASTPIN (3300 1775) SIG_NAME P5E_CPU0_PE2_TX_DN<7>
J 0
(3310 1785);
DISPLAY 0.659574 (3310 1785);
PAINT MONO (3310 1785);
DISPLAY INVISIBLE (3310 1785);
FORCEPROP 1 LASTPIN (3300 1775) BN 7
J 2
(3312 1783);
DISPLAY 0.680851 (3312 1783);
PAINT GREEN (3312 1783);
FORCEPROP 2 LAST CDS_LIB standard
J 0
(3250 1775);
DISPLAY INVISIBLE (3250 1775);
FORCEPROP 1 LAST BODY_TYPE PLUMBING
J 2
(3250 1825);
DISPLAY 0.872340 (3250 1825);
PAINT GREEN (3250 1825);
DISPLAY INVISIBLE (3250 1825);
FORCEPROP 1 LAST HDL_TAP TRUE
J 2
(2925 1650);
DISPLAY 0.872340 (2925 1650);
DISPLAY INVISIBLE (2925 1650);
FORCEPROP 1 LAST PATH I132
J 2
(3252 1775);
DISPLAY 0.872340 (3252 1775);
PAINT GREEN (3252 1775);
DISPLAY INVISIBLE (3252 1775);
FORCEADD Q_CAP_DIFFBUS..2
R 2
(3975 1375);
FORCEPROP 1 LAST PART_NUMBER SP_CH4221MEE01
J 2
(3859 1463);
DISPLAY 0.574468 (3859 1463);
PAINT GREEN (3859 1463);
DISPLAY INVISIBLE (3859 1463);
FORCEPROP 2 LAST VALUE DIFF BUS_0.22UF
J 2
(3825 1375);
DISPLAY 0.553191 (3825 1375);
FORCEPROP 1 LAST $LOCATION C954
J 2
(4209 1392);
DISPLAY 0.723404 (4209 1392);
PAINT GREEN (4209 1392);
FORCEPROP 2 LASTPIN (4050 1375) $PN 1
J 0
(4060 1385);
DISPLAY 0.808511 (4060 1385);
FORCEPROP 2 LASTPIN (3900 1375) $PN 2
J 2
(3890 1385);
DISPLAY 0.808511 (3890 1385);
FORCEPROP 2 LAST TOLERANCE 20%
J 2
(3900 1425);
DISPLAY 0.553191 (3900 1425);
DISPLAY INVISIBLE (3900 1425);
FORCEPROP 2 LAST PACK_TYPE C0201
J 2
(3800 1425);
DISPLAY 0.553191 (3800 1425);
DISPLAY INVISIBLE (3800 1425);
FORCEPROP 1 LAST MATERIAL X6S
J 2
(3984 1454);
DISPLAY 0.574468 (3984 1454);
PAINT GREEN (3984 1454);
DISPLAY INVISIBLE (3984 1454);
FORCEPROP 2 LAST VOLTAGE 6.3V
J 2
(3625 1425);
DISPLAY 0.553191 (3625 1425);
DISPLAY INVISIBLE (3625 1425);
FORCEPROP 1 LAST CDS_LMAN_SYM_OUTLINE -25,50,25,-50
J 2
(3975 1375);
DISPLAY 0.468085 (3975 1375);
PAINT GREEN (3975 1375);
DISPLAY INVISIBLE (3975 1375);
FORCEPROP 2 LAST CDS_LIB pure_quanta
J 2
(3975 1375);
DISPLAY INVISIBLE (3975 1375);
FORCEPROP 1 LAST PIN_NAMES_ROTATE TRUE
J 2
(3975 1375);
DISPLAY 0.489362 (3975 1375);
PAINT GREEN (3975 1375);
DISPLAY INVISIBLE (3975 1375);
FORCEPROP 1 LAST PATH I133
J 2
(3975 1375);
DISPLAY 0.723404 (3975 1375);
DISPLAY INVISIBLE (3975 1375);
FORCEPROP 1 LAST $LOCATION C954
J 0
(4225 1450);
DISPLAY 1.021277 (4225 1450);
DISPLAY INVISIBLE (4225 1450);
FORCEPROP 2 LAST CDS_LOCATION C954
J 0
(4225 1450);
DISPLAY 1.021277 (4225 1450);
DISPLAY INVISIBLE (4225 1450);
FORCEPROP 2 LAST $SEC 1
J 2
(4150 1450);
DISPLAY 0.680851 (4150 1450);
PAINT MONO (4150 1450);
DISPLAY INVISIBLE (4150 1450);
FORCEPROP 2 LAST CDS_SEC 1
J 2
(4150 1450);
DISPLAY 0.680851 (4150 1450);
DISPLAY INVISIBLE (4150 1450);
FORCEADD Q_CAP_DIFFBUS..2
R 2
(3975 1525);
FORCEPROP 1 LAST PART_NUMBER SP_CH4221MEE01
J 2
(3859 1613);
DISPLAY 0.574468 (3859 1613);
PAINT GREEN (3859 1613);
DISPLAY INVISIBLE (3859 1613);
FORCEPROP 2 LAST VALUE DIFF BUS_0.22UF
J 2
(3825 1525);
DISPLAY 0.553191 (3825 1525);
FORCEPROP 1 LAST $LOCATION C953
J 2
(4209 1542);
DISPLAY 0.723404 (4209 1542);
PAINT GREEN (4209 1542);
FORCEPROP 2 LASTPIN (4050 1525) $PN 1
J 0
(4060 1535);
DISPLAY 0.808511 (4060 1535);
FORCEPROP 2 LASTPIN (3900 1525) $PN 2
J 2
(3890 1535);
DISPLAY 0.808511 (3890 1535);
FORCEPROP 2 LAST TOLERANCE 20%
J 2
(3900 1575);
DISPLAY 0.553191 (3900 1575);
DISPLAY INVISIBLE (3900 1575);
FORCEPROP 2 LAST PACK_TYPE C0201
J 2
(3800 1575);
DISPLAY 0.553191 (3800 1575);
DISPLAY INVISIBLE (3800 1575);
FORCEPROP 1 LAST MATERIAL X6S
J 2
(3984 1604);
DISPLAY 0.574468 (3984 1604);
PAINT GREEN (3984 1604);
DISPLAY INVISIBLE (3984 1604);
FORCEPROP 2 LAST VOLTAGE 6.3V
J 2
(3625 1575);
DISPLAY 0.553191 (3625 1575);
DISPLAY INVISIBLE (3625 1575);
FORCEPROP 1 LAST CDS_LMAN_SYM_OUTLINE -25,50,25,-50
J 2
(3975 1525);
DISPLAY 0.468085 (3975 1525);
PAINT GREEN (3975 1525);
DISPLAY INVISIBLE (3975 1525);
FORCEPROP 2 LAST CDS_LIB pure_quanta
J 2
(3975 1525);
DISPLAY INVISIBLE (3975 1525);
FORCEPROP 1 LAST PIN_NAMES_ROTATE TRUE
J 2
(3975 1525);
DISPLAY 0.489362 (3975 1525);
PAINT GREEN (3975 1525);
DISPLAY INVISIBLE (3975 1525);
FORCEPROP 1 LAST PATH I134
J 2
(3975 1525);
DISPLAY 0.723404 (3975 1525);
DISPLAY INVISIBLE (3975 1525);
FORCEPROP 1 LAST $LOCATION C953
J 0
(4225 1600);
DISPLAY 1.021277 (4225 1600);
DISPLAY INVISIBLE (4225 1600);
FORCEPROP 2 LAST CDS_LOCATION C953
J 0
(4225 1600);
DISPLAY 1.021277 (4225 1600);
DISPLAY INVISIBLE (4225 1600);
FORCEPROP 2 LAST $SEC 1
J 2
(4150 1600);
DISPLAY 0.680851 (4150 1600);
PAINT MONO (4150 1600);
DISPLAY INVISIBLE (4150 1600);
FORCEPROP 2 LAST CDS_SEC 1
J 2
(4150 1600);
DISPLAY 0.680851 (4150 1600);
DISPLAY INVISIBLE (4150 1600);
FORCEADD Q_CAP_DIFFBUS..2
R 2
(3975 1575);
FORCEPROP 1 LAST PART_NUMBER SP_CH4221MEE01
J 2
(3859 1663);
DISPLAY 0.574468 (3859 1663);
PAINT GREEN (3859 1663);
DISPLAY INVISIBLE (3859 1663);
FORCEPROP 2 LAST VALUE DIFF BUS_0.22UF
J 2
(3825 1575);
DISPLAY 0.553191 (3825 1575);
FORCEPROP 1 LAST $LOCATION C952
J 2
(4209 1592);
DISPLAY 0.723404 (4209 1592);
PAINT GREEN (4209 1592);
FORCEPROP 2 LASTPIN (4050 1575) $PN 1
J 0
(4060 1585);
DISPLAY 0.808511 (4060 1585);
FORCEPROP 2 LASTPIN (3900 1575) $PN 2
J 2
(3890 1585);
DISPLAY 0.808511 (3890 1585);
FORCEPROP 2 LAST TOLERANCE 20%
J 2
(3900 1625);
DISPLAY 0.553191 (3900 1625);
DISPLAY INVISIBLE (3900 1625);
FORCEPROP 2 LAST PACK_TYPE C0201
J 2
(3800 1625);
DISPLAY 0.553191 (3800 1625);
DISPLAY INVISIBLE (3800 1625);
FORCEPROP 1 LAST MATERIAL X6S
J 2
(3984 1654);
DISPLAY 0.574468 (3984 1654);
PAINT GREEN (3984 1654);
DISPLAY INVISIBLE (3984 1654);
FORCEPROP 2 LAST VOLTAGE 6.3V
J 2
(3625 1625);
DISPLAY 0.553191 (3625 1625);
DISPLAY INVISIBLE (3625 1625);
FORCEPROP 1 LAST CDS_LMAN_SYM_OUTLINE -25,50,25,-50
J 2
(3975 1575);
DISPLAY 0.468085 (3975 1575);
PAINT GREEN (3975 1575);
DISPLAY INVISIBLE (3975 1575);
FORCEPROP 2 LAST CDS_LIB pure_quanta
J 2
(3975 1575);
DISPLAY INVISIBLE (3975 1575);
FORCEPROP 1 LAST PIN_NAMES_ROTATE TRUE
J 2
(3975 1575);
DISPLAY 0.489362 (3975 1575);
PAINT GREEN (3975 1575);
DISPLAY INVISIBLE (3975 1575);
FORCEPROP 1 LAST PATH I135
J 2
(3975 1575);
DISPLAY 0.723404 (3975 1575);
DISPLAY INVISIBLE (3975 1575);
FORCEPROP 1 LAST $LOCATION C952
J 0
(4225 1650);
DISPLAY 1.021277 (4225 1650);
DISPLAY INVISIBLE (4225 1650);
FORCEPROP 2 LAST CDS_LOCATION C952
J 0
(4225 1650);
DISPLAY 1.021277 (4225 1650);
DISPLAY INVISIBLE (4225 1650);
FORCEPROP 2 LAST $SEC 1
J 2
(4150 1650);
DISPLAY 0.680851 (4150 1650);
PAINT MONO (4150 1650);
DISPLAY INVISIBLE (4150 1650);
FORCEPROP 2 LAST CDS_SEC 1
J 2
(4150 1650);
DISPLAY 0.680851 (4150 1650);
DISPLAY INVISIBLE (4150 1650);
FORCEADD Q_CAP_DIFFBUS..2
R 2
(3975 1725);
FORCEPROP 1 LAST PART_NUMBER SP_CH4221MEE01
J 2
(3859 1813);
DISPLAY 0.574468 (3859 1813);
PAINT GREEN (3859 1813);
DISPLAY INVISIBLE (3859 1813);
FORCEPROP 2 LAST VALUE DIFF BUS_0.22UF
J 2
(3825 1725);
DISPLAY 0.553191 (3825 1725);
FORCEPROP 1 LAST $LOCATION C951
J 2
(4209 1742);
DISPLAY 0.723404 (4209 1742);
PAINT GREEN (4209 1742);
FORCEPROP 2 LASTPIN (4050 1725) $PN 1
J 0
(4060 1735);
DISPLAY 0.808511 (4060 1735);
FORCEPROP 2 LASTPIN (3900 1725) $PN 2
J 2
(3890 1735);
DISPLAY 0.808511 (3890 1735);
FORCEPROP 2 LAST TOLERANCE 20%
J 2
(3900 1775);
DISPLAY 0.553191 (3900 1775);
DISPLAY INVISIBLE (3900 1775);
FORCEPROP 2 LAST PACK_TYPE C0201
J 2
(3800 1775);
DISPLAY 0.553191 (3800 1775);
DISPLAY INVISIBLE (3800 1775);
FORCEPROP 1 LAST MATERIAL X6S
J 2
(3984 1804);
DISPLAY 0.574468 (3984 1804);
PAINT GREEN (3984 1804);
DISPLAY INVISIBLE (3984 1804);
FORCEPROP 2 LAST VOLTAGE 6.3V
J 2
(3625 1775);
DISPLAY 0.553191 (3625 1775);
DISPLAY INVISIBLE (3625 1775);
FORCEPROP 1 LAST CDS_LMAN_SYM_OUTLINE -25,50,25,-50
J 2
(3975 1725);
DISPLAY 0.468085 (3975 1725);
PAINT GREEN (3975 1725);
DISPLAY INVISIBLE (3975 1725);
FORCEPROP 2 LAST CDS_LIB pure_quanta
J 2
(3975 1725);
DISPLAY INVISIBLE (3975 1725);
FORCEPROP 1 LAST PIN_NAMES_ROTATE TRUE
J 2
(3975 1725);
DISPLAY 0.489362 (3975 1725);
PAINT GREEN (3975 1725);
DISPLAY INVISIBLE (3975 1725);
FORCEPROP 1 LAST PATH I136
J 2
(3975 1725);
DISPLAY 0.723404 (3975 1725);
DISPLAY INVISIBLE (3975 1725);
FORCEPROP 1 LAST $LOCATION C951
J 0
(4225 1800);
DISPLAY 1.021277 (4225 1800);
DISPLAY INVISIBLE (4225 1800);
FORCEPROP 2 LAST CDS_LOCATION C951
J 0
(4225 1800);
DISPLAY 1.021277 (4225 1800);
DISPLAY INVISIBLE (4225 1800);
FORCEPROP 2 LAST $SEC 1
J 2
(4150 1800);
DISPLAY 0.680851 (4150 1800);
PAINT MONO (4150 1800);
DISPLAY INVISIBLE (4150 1800);
FORCEPROP 2 LAST CDS_SEC 1
J 2
(4150 1800);
DISPLAY 0.680851 (4150 1800);
DISPLAY INVISIBLE (4150 1800);
FORCEADD Q_CAP_DIFFBUS..2
R 2
(3975 1775);
FORCEPROP 1 LAST PART_NUMBER SP_CH4221MEE01
J 2
(3859 1863);
DISPLAY 0.574468 (3859 1863);
PAINT GREEN (3859 1863);
DISPLAY INVISIBLE (3859 1863);
FORCEPROP 2 LAST VALUE DIFF BUS_0.22UF
J 2
(3825 1775);
DISPLAY 0.553191 (3825 1775);
FORCEPROP 1 LAST $LOCATION C950
J 2
(4209 1792);
DISPLAY 0.723404 (4209 1792);
PAINT GREEN (4209 1792);
FORCEPROP 2 LASTPIN (4050 1775) $PN 1
J 0
(4060 1785);
DISPLAY 0.808511 (4060 1785);
FORCEPROP 2 LASTPIN (3900 1775) $PN 2
J 2
(3890 1785);
DISPLAY 0.808511 (3890 1785);
FORCEPROP 2 LAST TOLERANCE 20%
J 2
(3900 1825);
DISPLAY 0.553191 (3900 1825);
DISPLAY INVISIBLE (3900 1825);
FORCEPROP 2 LAST PACK_TYPE C0201
J 2
(3800 1825);
DISPLAY 0.553191 (3800 1825);
DISPLAY INVISIBLE (3800 1825);
FORCEPROP 1 LAST MATERIAL X6S
J 2
(3984 1854);
DISPLAY 0.574468 (3984 1854);
PAINT GREEN (3984 1854);
DISPLAY INVISIBLE (3984 1854);
FORCEPROP 2 LAST VOLTAGE 6.3V
J 2
(3625 1825);
DISPLAY 0.553191 (3625 1825);
DISPLAY INVISIBLE (3625 1825);
FORCEPROP 2 LAST CDS_LIB pure_quanta
J 2
(3975 1775);
DISPLAY INVISIBLE (3975 1775);
FORCEPROP 1 LAST CDS_LMAN_SYM_OUTLINE -25,50,25,-50
J 2
(3975 1775);
DISPLAY 0.468085 (3975 1775);
PAINT GREEN (3975 1775);
DISPLAY INVISIBLE (3975 1775);
FORCEPROP 1 LAST PIN_NAMES_ROTATE TRUE
J 2
(3975 1775);
DISPLAY 0.489362 (3975 1775);
PAINT GREEN (3975 1775);
DISPLAY INVISIBLE (3975 1775);
FORCEPROP 1 LAST PATH I137
J 2
(3975 1775);
DISPLAY 0.723404 (3975 1775);
DISPLAY INVISIBLE (3975 1775);
FORCEPROP 1 LAST $LOCATION C950
J 0
(4225 1850);
DISPLAY 1.021277 (4225 1850);
DISPLAY INVISIBLE (4225 1850);
FORCEPROP 2 LAST CDS_LOCATION C950
J 0
(4225 1850);
DISPLAY 1.021277 (4225 1850);
DISPLAY INVISIBLE (4225 1850);
FORCEPROP 2 LAST $SEC 1
J 2
(4150 1850);
DISPLAY 0.680851 (4150 1850);
PAINT MONO (4150 1850);
DISPLAY INVISIBLE (4150 1850);
FORCEPROP 2 LAST CDS_SEC 1
J 2
(4150 1850);
DISPLAY 0.680851 (4150 1850);
DISPLAY INVISIBLE (4150 1850);
FORCEADD TAP..1
R 2
(3000 2500);
FORCEPROP 3 LASTPIN (3050 2500) SIG_NAME P5E_CPU0_PE2_TX_DP<9>
J 0
(3060 2510);
DISPLAY 0.659574 (3060 2510);
PAINT MONO (3060 2510);
DISPLAY INVISIBLE (3060 2510);
FORCEPROP 1 LASTPIN (3050 2500) BN 9
J 2
(3062 2508);
DISPLAY 0.680851 (3062 2508);
PAINT GREEN (3062 2508);
FORCEPROP 2 LAST CDS_LIB standard
J 0
(3000 2500);
DISPLAY INVISIBLE (3000 2500);
FORCEPROP 1 LAST BODY_TYPE PLUMBING
J 2
(3000 2550);
DISPLAY 0.872340 (3000 2550);
PAINT GREEN (3000 2550);
DISPLAY INVISIBLE (3000 2550);
FORCEPROP 1 LAST HDL_TAP TRUE
J 2
(2675 2375);
DISPLAY 0.872340 (2675 2375);
DISPLAY INVISIBLE (2675 2375);
FORCEPROP 1 LAST PATH I138
J 2
(3002 2500);
DISPLAY 0.872340 (3002 2500);
PAINT GREEN (3002 2500);
DISPLAY INVISIBLE (3002 2500);
FORCEADD TAP..1
R 2
(3000 2300);
FORCEPROP 3 LASTPIN (3050 2300) SIG_NAME P5E_CPU0_PE2_TX_DP<8>
J 0
(3060 2310);
DISPLAY 0.659574 (3060 2310);
PAINT MONO (3060 2310);
DISPLAY INVISIBLE (3060 2310);
FORCEPROP 1 LASTPIN (3050 2300) BN 8
J 2
(3062 2308);
DISPLAY 0.680851 (3062 2308);
PAINT GREEN (3062 2308);
FORCEPROP 2 LAST CDS_LIB standard
J 0
(3000 2300);
DISPLAY INVISIBLE (3000 2300);
FORCEPROP 1 LAST BODY_TYPE PLUMBING
J 2
(3000 2350);
DISPLAY 0.872340 (3000 2350);
PAINT GREEN (3000 2350);
DISPLAY INVISIBLE (3000 2350);
FORCEPROP 1 LAST HDL_TAP TRUE
J 2
(2675 2175);
DISPLAY 0.872340 (2675 2175);
DISPLAY INVISIBLE (2675 2175);
FORCEPROP 1 LAST PATH I139
J 2
(3002 2300);
DISPLAY 0.872340 (3002 2300);
PAINT GREEN (3002 2300);
DISPLAY INVISIBLE (3002 2300);
FORCEADD TAP..1
R 2
(-1550 1325);
FORCEPROP 3 LASTPIN (-1500 1325) SIG_NAME P5E_CPU0_PE0_TX_DP<5>
J 0
(-1490 1335);
DISPLAY 0.659574 (-1490 1335);
PAINT MONO (-1490 1335);
DISPLAY INVISIBLE (-1490 1335);
FORCEPROP 1 LASTPIN (-1500 1325) BN 5
J 2
(-1488 1333);
DISPLAY 0.680851 (-1488 1333);
PAINT GREEN (-1488 1333);
FORCEPROP 2 LAST CDS_LIB standard
J 0
(-1550 1325);
DISPLAY INVISIBLE (-1550 1325);
FORCEPROP 1 LAST BODY_TYPE PLUMBING
J 2
(-1550 1375);
DISPLAY 0.872340 (-1550 1375);
PAINT GREEN (-1550 1375);
DISPLAY INVISIBLE (-1550 1375);
FORCEPROP 1 LAST HDL_TAP TRUE
J 2
(-1875 1200);
DISPLAY 0.872340 (-1875 1200);
DISPLAY INVISIBLE (-1875 1200);
FORCEPROP 1 LAST PATH I14
J 2
(-1548 1325);
DISPLAY 0.872340 (-1548 1325);
PAINT GREEN (-1548 1325);
DISPLAY INVISIBLE (-1548 1325);
FORCEADD TAP..1
R 2
(3000 3100);
FORCEPROP 3 LASTPIN (3050 3100) SIG_NAME P5E_CPU0_PE2_TX_DP<12>
J 0
(3060 3110);
DISPLAY 0.659574 (3060 3110);
PAINT MONO (3060 3110);
DISPLAY INVISIBLE (3060 3110);
FORCEPROP 1 LASTPIN (3050 3100) BN 12
J 2
(3062 3108);
DISPLAY 0.680851 (3062 3108);
PAINT GREEN (3062 3108);
FORCEPROP 2 LAST CDS_LIB standard
J 0
(3000 3100);
DISPLAY INVISIBLE (3000 3100);
FORCEPROP 1 LAST BODY_TYPE PLUMBING
J 2
(3000 3150);
DISPLAY 0.872340 (3000 3150);
PAINT GREEN (3000 3150);
DISPLAY INVISIBLE (3000 3150);
FORCEPROP 1 LAST HDL_TAP TRUE
J 2
(2675 2975);
DISPLAY 0.872340 (2675 2975);
DISPLAY INVISIBLE (2675 2975);
FORCEPROP 1 LAST PATH I140
J 2
(3002 3100);
DISPLAY 0.872340 (3002 3100);
PAINT GREEN (3002 3100);
DISPLAY INVISIBLE (3002 3100);
FORCEADD TAP..1
R 2
(3000 2900);
FORCEPROP 3 LASTPIN (3050 2900) SIG_NAME P5E_CPU0_PE2_TX_DP<11>
J 0
(3060 2910);
DISPLAY 0.659574 (3060 2910);
PAINT MONO (3060 2910);
DISPLAY INVISIBLE (3060 2910);
FORCEPROP 1 LASTPIN (3050 2900) BN 11
J 2
(3062 2908);
DISPLAY 0.680851 (3062 2908);
PAINT GREEN (3062 2908);
FORCEPROP 2 LAST CDS_LIB standard
J 0
(3000 2900);
DISPLAY INVISIBLE (3000 2900);
FORCEPROP 1 LAST BODY_TYPE PLUMBING
J 2
(3000 2950);
DISPLAY 0.872340 (3000 2950);
PAINT GREEN (3000 2950);
DISPLAY INVISIBLE (3000 2950);
FORCEPROP 1 LAST HDL_TAP TRUE
J 2
(2675 2775);
DISPLAY 0.872340 (2675 2775);
DISPLAY INVISIBLE (2675 2775);
FORCEPROP 1 LAST PATH I141
J 2
(3002 2900);
DISPLAY 0.872340 (3002 2900);
PAINT GREEN (3002 2900);
DISPLAY INVISIBLE (3002 2900);
FORCEADD TAP..1
R 2
(3000 2700);
FORCEPROP 3 LASTPIN (3050 2700) SIG_NAME P5E_CPU0_PE2_TX_DP<10>
J 0
(3060 2710);
DISPLAY 0.659574 (3060 2710);
PAINT MONO (3060 2710);
DISPLAY INVISIBLE (3060 2710);
FORCEPROP 1 LASTPIN (3050 2700) BN 10
J 2
(3062 2708);
DISPLAY 0.680851 (3062 2708);
PAINT GREEN (3062 2708);
FORCEPROP 2 LAST CDS_LIB standard
J 0
(3000 2700);
DISPLAY INVISIBLE (3000 2700);
FORCEPROP 1 LAST BODY_TYPE PLUMBING
J 2
(3000 2750);
DISPLAY 0.872340 (3000 2750);
PAINT GREEN (3000 2750);
DISPLAY INVISIBLE (3000 2750);
FORCEPROP 1 LAST HDL_TAP TRUE
J 2
(2675 2575);
DISPLAY 0.872340 (2675 2575);
DISPLAY INVISIBLE (2675 2575);
FORCEPROP 1 LAST PATH I142
J 2
(3002 2700);
DISPLAY 0.872340 (3002 2700);
PAINT GREEN (3002 2700);
DISPLAY INVISIBLE (3002 2700);
FORCEADD TAP..1
R 2
(3000 3300);
FORCEPROP 3 LASTPIN (3050 3300) SIG_NAME P5E_CPU0_PE2_TX_DP<13>
J 0
(3060 3310);
DISPLAY 0.659574 (3060 3310);
PAINT MONO (3060 3310);
DISPLAY INVISIBLE (3060 3310);
FORCEPROP 1 LASTPIN (3050 3300) BN 13
J 2
(3062 3308);
DISPLAY 0.680851 (3062 3308);
PAINT GREEN (3062 3308);
FORCEPROP 2 LAST CDS_LIB standard
J 0
(3000 3300);
DISPLAY INVISIBLE (3000 3300);
FORCEPROP 1 LAST BODY_TYPE PLUMBING
J 2
(3000 3350);
DISPLAY 0.872340 (3000 3350);
PAINT GREEN (3000 3350);
DISPLAY INVISIBLE (3000 3350);
FORCEPROP 1 LAST HDL_TAP TRUE
J 2
(2675 3175);
DISPLAY 0.872340 (2675 3175);
DISPLAY INVISIBLE (2675 3175);
FORCEPROP 1 LAST PATH I143
J 2
(3002 3300);
DISPLAY 0.872340 (3002 3300);
PAINT GREEN (3002 3300);
DISPLAY INVISIBLE (3002 3300);
FORCEADD TAP..1
R 2
(3000 3500);
FORCEPROP 3 LASTPIN (3050 3500) SIG_NAME P5E_CPU0_PE2_TX_DP<14>
J 0
(3060 3510);
DISPLAY 0.659574 (3060 3510);
PAINT MONO (3060 3510);
DISPLAY INVISIBLE (3060 3510);
FORCEPROP 1 LASTPIN (3050 3500) BN 14
J 2
(3062 3508);
DISPLAY 0.680851 (3062 3508);
PAINT GREEN (3062 3508);
FORCEPROP 2 LAST CDS_LIB standard
J 0
(3000 3500);
DISPLAY INVISIBLE (3000 3500);
FORCEPROP 1 LAST BODY_TYPE PLUMBING
J 2
(3000 3550);
DISPLAY 0.872340 (3000 3550);
PAINT GREEN (3000 3550);
DISPLAY INVISIBLE (3000 3550);
FORCEPROP 1 LAST HDL_TAP TRUE
J 2
(2675 3375);
DISPLAY 0.872340 (2675 3375);
DISPLAY INVISIBLE (2675 3375);
FORCEPROP 1 LAST PATH I144
J 2
(3002 3500);
DISPLAY 0.872340 (3002 3500);
PAINT GREEN (3002 3500);
DISPLAY INVISIBLE (3002 3500);
FORCEADD TAP..1
R 2
(3000 3700);
FORCEPROP 3 LASTPIN (3050 3700) SIG_NAME P5E_CPU0_PE2_TX_DP<15>
J 0
(3060 3710);
DISPLAY 0.659574 (3060 3710);
PAINT MONO (3060 3710);
DISPLAY INVISIBLE (3060 3710);
FORCEPROP 1 LASTPIN (3050 3700) BN 15
J 2
(3062 3708);
DISPLAY 0.680851 (3062 3708);
PAINT GREEN (3062 3708);
FORCEPROP 2 LAST CDS_LIB standard
J 0
(3000 3700);
DISPLAY INVISIBLE (3000 3700);
FORCEPROP 1 LAST BODY_TYPE PLUMBING
J 2
(3000 3750);
DISPLAY 0.872340 (3000 3750);
PAINT GREEN (3000 3750);
DISPLAY INVISIBLE (3000 3750);
FORCEPROP 1 LAST HDL_TAP TRUE
J 2
(2675 3575);
DISPLAY 0.872340 (2675 3575);
DISPLAY INVISIBLE (2675 3575);
FORCEPROP 1 LAST PATH I145
J 2
(3002 3700);
DISPLAY 0.872340 (3002 3700);
PAINT GREEN (3002 3700);
DISPLAY INVISIBLE (3002 3700);
FORCEADD TAP..1
R 2
(3250 2350);
FORCEPROP 3 LASTPIN (3300 2350) SIG_NAME P5E_CPU0_PE2_TX_DN<8>
J 0
(3310 2360);
DISPLAY 0.659574 (3310 2360);
PAINT MONO (3310 2360);
DISPLAY INVISIBLE (3310 2360);
FORCEPROP 1 LASTPIN (3300 2350) BN 8
J 2
(3312 2358);
DISPLAY 0.680851 (3312 2358);
PAINT GREEN (3312 2358);
FORCEPROP 2 LAST CDS_LIB standard
J 0
(3250 2350);
DISPLAY INVISIBLE (3250 2350);
FORCEPROP 1 LAST BODY_TYPE PLUMBING
J 2
(3250 2400);
DISPLAY 0.872340 (3250 2400);
PAINT GREEN (3250 2400);
DISPLAY INVISIBLE (3250 2400);
FORCEPROP 1 LAST HDL_TAP TRUE
J 2
(2925 2225);
DISPLAY 0.872340 (2925 2225);
DISPLAY INVISIBLE (2925 2225);
FORCEPROP 1 LAST PATH I146
J 2
(3252 2350);
DISPLAY 0.872340 (3252 2350);
PAINT GREEN (3252 2350);
DISPLAY INVISIBLE (3252 2350);
FORCEADD TAP..1
R 2
(3250 2550);
FORCEPROP 3 LASTPIN (3300 2550) SIG_NAME P5E_CPU0_PE2_TX_DN<9>
J 0
(3310 2560);
DISPLAY 0.659574 (3310 2560);
PAINT MONO (3310 2560);
DISPLAY INVISIBLE (3310 2560);
FORCEPROP 1 LASTPIN (3300 2550) BN 9
J 2
(3312 2558);
DISPLAY 0.680851 (3312 2558);
PAINT GREEN (3312 2558);
FORCEPROP 2 LAST CDS_LIB standard
J 0
(3250 2550);
DISPLAY INVISIBLE (3250 2550);
FORCEPROP 1 LAST BODY_TYPE PLUMBING
J 2
(3250 2600);
DISPLAY 0.872340 (3250 2600);
PAINT GREEN (3250 2600);
DISPLAY INVISIBLE (3250 2600);
FORCEPROP 1 LAST HDL_TAP TRUE
J 2
(2925 2425);
DISPLAY 0.872340 (2925 2425);
DISPLAY INVISIBLE (2925 2425);
FORCEPROP 1 LAST PATH I147
J 2
(3252 2550);
DISPLAY 0.872340 (3252 2550);
PAINT GREEN (3252 2550);
DISPLAY INVISIBLE (3252 2550);
FORCEADD TAP..1
R 2
(3250 2750);
FORCEPROP 3 LASTPIN (3300 2750) SIG_NAME P5E_CPU0_PE2_TX_DN<10>
J 0
(3310 2760);
DISPLAY 0.659574 (3310 2760);
PAINT MONO (3310 2760);
DISPLAY INVISIBLE (3310 2760);
FORCEPROP 1 LASTPIN (3300 2750) BN 10
J 2
(3312 2758);
DISPLAY 0.680851 (3312 2758);
PAINT GREEN (3312 2758);
FORCEPROP 2 LAST CDS_LIB standard
J 0
(3250 2750);
DISPLAY INVISIBLE (3250 2750);
FORCEPROP 1 LAST BODY_TYPE PLUMBING
J 2
(3250 2800);
DISPLAY 0.872340 (3250 2800);
PAINT GREEN (3250 2800);
DISPLAY INVISIBLE (3250 2800);
FORCEPROP 1 LAST HDL_TAP TRUE
J 2
(2925 2625);
DISPLAY 0.872340 (2925 2625);
DISPLAY INVISIBLE (2925 2625);
FORCEPROP 1 LAST PATH I148
J 2
(3252 2750);
DISPLAY 0.872340 (3252 2750);
PAINT GREEN (3252 2750);
DISPLAY INVISIBLE (3252 2750);
FORCEADD TAP..1
R 2
(3250 2950);
FORCEPROP 3 LASTPIN (3300 2950) SIG_NAME P5E_CPU0_PE2_TX_DN<11>
J 0
(3310 2960);
DISPLAY 0.659574 (3310 2960);
PAINT MONO (3310 2960);
DISPLAY INVISIBLE (3310 2960);
FORCEPROP 1 LASTPIN (3300 2950) BN 11
J 2
(3312 2958);
DISPLAY 0.680851 (3312 2958);
PAINT GREEN (3312 2958);
FORCEPROP 2 LAST CDS_LIB standard
J 0
(3250 2950);
DISPLAY INVISIBLE (3250 2950);
FORCEPROP 1 LAST BODY_TYPE PLUMBING
J 2
(3250 3000);
DISPLAY 0.872340 (3250 3000);
PAINT GREEN (3250 3000);
DISPLAY INVISIBLE (3250 3000);
FORCEPROP 1 LAST HDL_TAP TRUE
J 2
(2925 2825);
DISPLAY 0.872340 (2925 2825);
DISPLAY INVISIBLE (2925 2825);
FORCEPROP 1 LAST PATH I149
J 2
(3252 2950);
DISPLAY 0.872340 (3252 2950);
PAINT GREEN (3252 2950);
DISPLAY INVISIBLE (3252 2950);
FORCEADD TAP..1
R 2
(-1550 1525);
FORCEPROP 3 LASTPIN (-1500 1525) SIG_NAME P5E_CPU0_PE0_TX_DP<6>
J 0
(-1490 1535);
DISPLAY 0.659574 (-1490 1535);
PAINT MONO (-1490 1535);
DISPLAY INVISIBLE (-1490 1535);
FORCEPROP 1 LASTPIN (-1500 1525) BN 6
J 2
(-1488 1533);
DISPLAY 0.680851 (-1488 1533);
PAINT GREEN (-1488 1533);
FORCEPROP 2 LAST CDS_LIB standard
J 0
(-1550 1525);
DISPLAY INVISIBLE (-1550 1525);
FORCEPROP 1 LAST BODY_TYPE PLUMBING
J 2
(-1550 1575);
DISPLAY 0.872340 (-1550 1575);
PAINT GREEN (-1550 1575);
DISPLAY INVISIBLE (-1550 1575);
FORCEPROP 1 LAST HDL_TAP TRUE
J 2
(-1875 1400);
DISPLAY 0.872340 (-1875 1400);
DISPLAY INVISIBLE (-1875 1400);
FORCEPROP 1 LAST PATH I15
J 2
(-1548 1525);
DISPLAY 0.872340 (-1548 1525);
PAINT GREEN (-1548 1525);
DISPLAY INVISIBLE (-1548 1525);
FORCEADD TAP..1
R 2
(3250 3150);
FORCEPROP 3 LASTPIN (3300 3150) SIG_NAME P5E_CPU0_PE2_TX_DN<12>
J 0
(3310 3160);
DISPLAY 0.659574 (3310 3160);
PAINT MONO (3310 3160);
DISPLAY INVISIBLE (3310 3160);
FORCEPROP 1 LASTPIN (3300 3150) BN 12
J 2
(3312 3158);
DISPLAY 0.680851 (3312 3158);
PAINT GREEN (3312 3158);
FORCEPROP 2 LAST CDS_LIB standard
J 0
(3250 3150);
DISPLAY INVISIBLE (3250 3150);
FORCEPROP 1 LAST BODY_TYPE PLUMBING
J 2
(3250 3200);
DISPLAY 0.872340 (3250 3200);
PAINT GREEN (3250 3200);
DISPLAY INVISIBLE (3250 3200);
FORCEPROP 1 LAST HDL_TAP TRUE
J 2
(2925 3025);
DISPLAY 0.872340 (2925 3025);
DISPLAY INVISIBLE (2925 3025);
FORCEPROP 1 LAST PATH I150
J 2
(3252 3150);
DISPLAY 0.872340 (3252 3150);
PAINT GREEN (3252 3150);
DISPLAY INVISIBLE (3252 3150);
FORCEADD Q_CAP_DIFFBUS..2
R 2
(3975 2300);
FORCEPROP 1 LAST PART_NUMBER SP_CH4221MEE01
J 2
(3859 2388);
DISPLAY 0.574468 (3859 2388);
PAINT GREEN (3859 2388);
DISPLAY INVISIBLE (3859 2388);
FORCEPROP 2 LAST VALUE DIFF BUS_0.22UF
J 2
(3825 2300);
DISPLAY 0.553191 (3825 2300);
FORCEPROP 1 LAST $LOCATION C949
J 2
(4209 2317);
DISPLAY 0.723404 (4209 2317);
PAINT GREEN (4209 2317);
FORCEPROP 2 LASTPIN (4050 2300) $PN 1
J 0
(4060 2310);
DISPLAY 0.808511 (4060 2310);
FORCEPROP 2 LASTPIN (3900 2300) $PN 2
J 2
(3890 2310);
DISPLAY 0.808511 (3890 2310);
FORCEPROP 2 LAST TOLERANCE 20%
J 2
(3900 2350);
DISPLAY 0.553191 (3900 2350);
DISPLAY INVISIBLE (3900 2350);
FORCEPROP 2 LAST PACK_TYPE C0201
J 2
(3800 2350);
DISPLAY 0.553191 (3800 2350);
DISPLAY INVISIBLE (3800 2350);
FORCEPROP 1 LAST MATERIAL X6S
J 2
(3984 2379);
DISPLAY 0.574468 (3984 2379);
PAINT GREEN (3984 2379);
DISPLAY INVISIBLE (3984 2379);
FORCEPROP 2 LAST VOLTAGE 6.3V
J 2
(3625 2350);
DISPLAY 0.553191 (3625 2350);
DISPLAY INVISIBLE (3625 2350);
FORCEPROP 1 LAST PIN_NAMES_ROTATE TRUE
J 2
(3975 2300);
DISPLAY 0.489362 (3975 2300);
PAINT GREEN (3975 2300);
DISPLAY INVISIBLE (3975 2300);
FORCEPROP 2 LAST CDS_LIB pure_quanta
J 2
(3975 2300);
DISPLAY INVISIBLE (3975 2300);
FORCEPROP 1 LAST CDS_LMAN_SYM_OUTLINE -25,50,25,-50
J 2
(3975 2300);
DISPLAY 0.468085 (3975 2300);
PAINT GREEN (3975 2300);
DISPLAY INVISIBLE (3975 2300);
FORCEPROP 1 LAST PATH I151
J 2
(3975 2300);
DISPLAY 0.723404 (3975 2300);
DISPLAY INVISIBLE (3975 2300);
FORCEPROP 1 LAST $LOCATION C949
J 0
(4225 2375);
DISPLAY 1.021277 (4225 2375);
DISPLAY INVISIBLE (4225 2375);
FORCEPROP 2 LAST CDS_LOCATION C949
J 0
(4225 2375);
DISPLAY 1.021277 (4225 2375);
DISPLAY INVISIBLE (4225 2375);
FORCEPROP 2 LAST $SEC 1
J 2
(4150 2375);
DISPLAY 0.680851 (4150 2375);
PAINT MONO (4150 2375);
DISPLAY INVISIBLE (4150 2375);
FORCEPROP 2 LAST CDS_SEC 1
J 2
(4150 2375);
DISPLAY 0.680851 (4150 2375);
DISPLAY INVISIBLE (4150 2375);
FORCEADD Q_CAP_DIFFBUS..2
R 2
(3975 2350);
FORCEPROP 1 LAST PART_NUMBER SP_CH4221MEE01
J 2
(3859 2438);
DISPLAY 0.574468 (3859 2438);
PAINT GREEN (3859 2438);
DISPLAY INVISIBLE (3859 2438);
FORCEPROP 2 LAST VALUE DIFF BUS_0.22UF
J 2
(3825 2350);
DISPLAY 0.553191 (3825 2350);
FORCEPROP 1 LAST $LOCATION C948
J 2
(4209 2367);
DISPLAY 0.723404 (4209 2367);
PAINT GREEN (4209 2367);
FORCEPROP 2 LASTPIN (4050 2350) $PN 1
J 0
(4060 2360);
DISPLAY 0.808511 (4060 2360);
FORCEPROP 2 LASTPIN (3900 2350) $PN 2
J 2
(3890 2360);
DISPLAY 0.808511 (3890 2360);
FORCEPROP 2 LAST TOLERANCE 20%
J 2
(3900 2400);
DISPLAY 0.553191 (3900 2400);
DISPLAY INVISIBLE (3900 2400);
FORCEPROP 2 LAST PACK_TYPE C0201
J 2
(3800 2400);
DISPLAY 0.553191 (3800 2400);
DISPLAY INVISIBLE (3800 2400);
FORCEPROP 1 LAST MATERIAL X6S
J 2
(3984 2429);
DISPLAY 0.574468 (3984 2429);
PAINT GREEN (3984 2429);
DISPLAY INVISIBLE (3984 2429);
FORCEPROP 2 LAST VOLTAGE 6.3V
J 2
(3625 2400);
DISPLAY 0.553191 (3625 2400);
DISPLAY INVISIBLE (3625 2400);
FORCEPROP 1 LAST PIN_NAMES_ROTATE TRUE
J 2
(3975 2350);
DISPLAY 0.489362 (3975 2350);
PAINT GREEN (3975 2350);
DISPLAY INVISIBLE (3975 2350);
FORCEPROP 2 LAST CDS_LIB pure_quanta
J 2
(3975 2350);
DISPLAY INVISIBLE (3975 2350);
FORCEPROP 1 LAST CDS_LMAN_SYM_OUTLINE -25,50,25,-50
J 2
(3975 2350);
DISPLAY 0.468085 (3975 2350);
PAINT GREEN (3975 2350);
DISPLAY INVISIBLE (3975 2350);
FORCEPROP 1 LAST PATH I152
J 2
(3975 2350);
DISPLAY 0.723404 (3975 2350);
DISPLAY INVISIBLE (3975 2350);
FORCEPROP 1 LAST $LOCATION C948
J 0
(4225 2425);
DISPLAY 1.021277 (4225 2425);
DISPLAY INVISIBLE (4225 2425);
FORCEPROP 2 LAST CDS_LOCATION C948
J 0
(4225 2425);
DISPLAY 1.021277 (4225 2425);
DISPLAY INVISIBLE (4225 2425);
FORCEPROP 2 LAST $SEC 1
J 2
(4150 2425);
DISPLAY 0.680851 (4150 2425);
PAINT MONO (4150 2425);
DISPLAY INVISIBLE (4150 2425);
FORCEPROP 2 LAST CDS_SEC 1
J 2
(4150 2425);
DISPLAY 0.680851 (4150 2425);
DISPLAY INVISIBLE (4150 2425);
FORCEADD Q_CAP_DIFFBUS..2
R 2
(3975 2500);
FORCEPROP 1 LAST PART_NUMBER SP_CH4221MEE01
J 2
(3859 2588);
DISPLAY 0.574468 (3859 2588);
PAINT GREEN (3859 2588);
DISPLAY INVISIBLE (3859 2588);
FORCEPROP 2 LAST VALUE DIFF BUS_0.22UF
J 2
(3825 2500);
DISPLAY 0.553191 (3825 2500);
FORCEPROP 1 LAST $LOCATION C947
J 2
(4209 2517);
DISPLAY 0.723404 (4209 2517);
PAINT GREEN (4209 2517);
FORCEPROP 2 LASTPIN (4050 2500) $PN 1
J 0
(4060 2510);
DISPLAY 0.808511 (4060 2510);
FORCEPROP 2 LASTPIN (3900 2500) $PN 2
J 2
(3890 2510);
DISPLAY 0.808511 (3890 2510);
FORCEPROP 2 LAST TOLERANCE 20%
J 2
(3900 2550);
DISPLAY 0.553191 (3900 2550);
DISPLAY INVISIBLE (3900 2550);
FORCEPROP 2 LAST PACK_TYPE C0201
J 2
(3800 2550);
DISPLAY 0.553191 (3800 2550);
DISPLAY INVISIBLE (3800 2550);
FORCEPROP 1 LAST MATERIAL X6S
J 2
(3984 2579);
DISPLAY 0.574468 (3984 2579);
PAINT GREEN (3984 2579);
DISPLAY INVISIBLE (3984 2579);
FORCEPROP 2 LAST VOLTAGE 6.3V
J 2
(3625 2550);
DISPLAY 0.553191 (3625 2550);
DISPLAY INVISIBLE (3625 2550);
FORCEPROP 1 LAST PIN_NAMES_ROTATE TRUE
J 2
(3975 2500);
DISPLAY 0.489362 (3975 2500);
PAINT GREEN (3975 2500);
DISPLAY INVISIBLE (3975 2500);
FORCEPROP 2 LAST CDS_LIB pure_quanta
J 2
(3975 2500);
DISPLAY INVISIBLE (3975 2500);
FORCEPROP 1 LAST CDS_LMAN_SYM_OUTLINE -25,50,25,-50
J 2
(3975 2500);
DISPLAY 0.468085 (3975 2500);
PAINT GREEN (3975 2500);
DISPLAY INVISIBLE (3975 2500);
FORCEPROP 1 LAST PATH I153
J 2
(3975 2500);
DISPLAY 0.723404 (3975 2500);
DISPLAY INVISIBLE (3975 2500);
FORCEPROP 1 LAST $LOCATION C947
J 0
(4225 2575);
DISPLAY 1.021277 (4225 2575);
DISPLAY INVISIBLE (4225 2575);
FORCEPROP 2 LAST CDS_LOCATION C947
J 0
(4225 2575);
DISPLAY 1.021277 (4225 2575);
DISPLAY INVISIBLE (4225 2575);
FORCEPROP 2 LAST $SEC 1
J 2
(4150 2575);
DISPLAY 0.680851 (4150 2575);
PAINT MONO (4150 2575);
DISPLAY INVISIBLE (4150 2575);
FORCEPROP 2 LAST CDS_SEC 1
J 2
(4150 2575);
DISPLAY 0.680851 (4150 2575);
DISPLAY INVISIBLE (4150 2575);
FORCEADD Q_CAP_DIFFBUS..2
R 2
(3975 2550);
FORCEPROP 1 LAST PART_NUMBER SP_CH4221MEE01
J 2
(3859 2638);
DISPLAY 0.574468 (3859 2638);
PAINT GREEN (3859 2638);
DISPLAY INVISIBLE (3859 2638);
FORCEPROP 2 LAST VALUE DIFF BUS_0.22UF
J 2
(3825 2550);
DISPLAY 0.553191 (3825 2550);
FORCEPROP 1 LAST $LOCATION C946
J 2
(4209 2567);
DISPLAY 0.723404 (4209 2567);
PAINT GREEN (4209 2567);
FORCEPROP 2 LASTPIN (4050 2550) $PN 1
J 0
(4060 2560);
DISPLAY 0.808511 (4060 2560);
FORCEPROP 2 LASTPIN (3900 2550) $PN 2
J 2
(3890 2560);
DISPLAY 0.808511 (3890 2560);
FORCEPROP 2 LAST TOLERANCE 20%
J 2
(3900 2600);
DISPLAY 0.553191 (3900 2600);
DISPLAY INVISIBLE (3900 2600);
FORCEPROP 2 LAST PACK_TYPE C0201
J 2
(3800 2600);
DISPLAY 0.553191 (3800 2600);
DISPLAY INVISIBLE (3800 2600);
FORCEPROP 1 LAST MATERIAL X6S
J 2
(3984 2629);
DISPLAY 0.574468 (3984 2629);
PAINT GREEN (3984 2629);
DISPLAY INVISIBLE (3984 2629);
FORCEPROP 2 LAST VOLTAGE 6.3V
J 2
(3625 2600);
DISPLAY 0.553191 (3625 2600);
DISPLAY INVISIBLE (3625 2600);
FORCEPROP 1 LAST PIN_NAMES_ROTATE TRUE
J 2
(3975 2550);
DISPLAY 0.489362 (3975 2550);
PAINT GREEN (3975 2550);
DISPLAY INVISIBLE (3975 2550);
FORCEPROP 1 LAST CDS_LMAN_SYM_OUTLINE -25,50,25,-50
J 2
(3975 2550);
DISPLAY 0.468085 (3975 2550);
PAINT GREEN (3975 2550);
DISPLAY INVISIBLE (3975 2550);
FORCEPROP 2 LAST CDS_LIB pure_quanta
J 2
(3975 2550);
DISPLAY INVISIBLE (3975 2550);
FORCEPROP 1 LAST PATH I154
J 2
(3975 2550);
DISPLAY 0.723404 (3975 2550);
DISPLAY INVISIBLE (3975 2550);
FORCEPROP 1 LAST $LOCATION C946
J 0
(4225 2625);
DISPLAY 1.021277 (4225 2625);
DISPLAY INVISIBLE (4225 2625);
FORCEPROP 2 LAST CDS_LOCATION C946
J 0
(4225 2625);
DISPLAY 1.021277 (4225 2625);
DISPLAY INVISIBLE (4225 2625);
FORCEPROP 2 LAST $SEC 1
J 2
(4150 2625);
DISPLAY 0.680851 (4150 2625);
PAINT MONO (4150 2625);
DISPLAY INVISIBLE (4150 2625);
FORCEPROP 2 LAST CDS_SEC 1
J 2
(4150 2625);
DISPLAY 0.680851 (4150 2625);
DISPLAY INVISIBLE (4150 2625);
FORCEADD Q_CAP_DIFFBUS..2
R 2
(3975 2700);
FORCEPROP 1 LAST PART_NUMBER SP_CH4221MEE01
J 2
(3859 2788);
DISPLAY 0.574468 (3859 2788);
PAINT GREEN (3859 2788);
DISPLAY INVISIBLE (3859 2788);
FORCEPROP 2 LAST VALUE DIFF BUS_0.22UF
J 2
(3825 2700);
DISPLAY 0.553191 (3825 2700);
FORCEPROP 1 LAST $LOCATION C945
J 2
(4209 2717);
DISPLAY 0.723404 (4209 2717);
PAINT GREEN (4209 2717);
FORCEPROP 2 LASTPIN (4050 2700) $PN 1
J 0
(4060 2710);
DISPLAY 0.808511 (4060 2710);
FORCEPROP 2 LASTPIN (3900 2700) $PN 2
J 2
(3890 2710);
DISPLAY 0.808511 (3890 2710);
FORCEPROP 2 LAST TOLERANCE 20%
J 2
(3900 2750);
DISPLAY 0.553191 (3900 2750);
DISPLAY INVISIBLE (3900 2750);
FORCEPROP 2 LAST PACK_TYPE C0201
J 2
(3800 2750);
DISPLAY 0.553191 (3800 2750);
DISPLAY INVISIBLE (3800 2750);
FORCEPROP 1 LAST MATERIAL X6S
J 2
(3984 2779);
DISPLAY 0.574468 (3984 2779);
PAINT GREEN (3984 2779);
DISPLAY INVISIBLE (3984 2779);
FORCEPROP 2 LAST VOLTAGE 6.3V
J 2
(3625 2750);
DISPLAY 0.553191 (3625 2750);
DISPLAY INVISIBLE (3625 2750);
FORCEPROP 1 LAST PIN_NAMES_ROTATE TRUE
J 2
(3975 2700);
DISPLAY 0.489362 (3975 2700);
PAINT GREEN (3975 2700);
DISPLAY INVISIBLE (3975 2700);
FORCEPROP 2 LAST CDS_LIB pure_quanta
J 2
(3975 2700);
DISPLAY INVISIBLE (3975 2700);
FORCEPROP 1 LAST CDS_LMAN_SYM_OUTLINE -25,50,25,-50
J 2
(3975 2700);
DISPLAY 0.468085 (3975 2700);
PAINT GREEN (3975 2700);
DISPLAY INVISIBLE (3975 2700);
FORCEPROP 1 LAST PATH I155
J 2
(3975 2700);
DISPLAY 0.723404 (3975 2700);
DISPLAY INVISIBLE (3975 2700);
FORCEPROP 1 LAST $LOCATION C945
J 0
(4225 2775);
DISPLAY 1.021277 (4225 2775);
DISPLAY INVISIBLE (4225 2775);
FORCEPROP 2 LAST CDS_LOCATION C945
J 0
(4225 2775);
DISPLAY 1.021277 (4225 2775);
DISPLAY INVISIBLE (4225 2775);
FORCEPROP 2 LAST $SEC 1
J 2
(4150 2775);
DISPLAY 0.680851 (4150 2775);
PAINT MONO (4150 2775);
DISPLAY INVISIBLE (4150 2775);
FORCEPROP 2 LAST CDS_SEC 1
J 2
(4150 2775);
DISPLAY 0.680851 (4150 2775);
DISPLAY INVISIBLE (4150 2775);
FORCEADD Q_CAP_DIFFBUS..2
R 2
(3975 2750);
FORCEPROP 1 LAST PART_NUMBER SP_CH4221MEE01
J 2
(3859 2838);
DISPLAY 0.574468 (3859 2838);
PAINT GREEN (3859 2838);
DISPLAY INVISIBLE (3859 2838);
FORCEPROP 2 LAST VALUE DIFF BUS_0.22UF
J 2
(3825 2750);
DISPLAY 0.553191 (3825 2750);
FORCEPROP 1 LAST $LOCATION C944
J 2
(4209 2767);
DISPLAY 0.723404 (4209 2767);
PAINT GREEN (4209 2767);
FORCEPROP 2 LASTPIN (4050 2750) $PN 1
J 0
(4060 2760);
DISPLAY 0.808511 (4060 2760);
FORCEPROP 2 LASTPIN (3900 2750) $PN 2
J 2
(3890 2760);
DISPLAY 0.808511 (3890 2760);
FORCEPROP 2 LAST TOLERANCE 20%
J 2
(3900 2800);
DISPLAY 0.553191 (3900 2800);
DISPLAY INVISIBLE (3900 2800);
FORCEPROP 2 LAST PACK_TYPE C0201
J 2
(3800 2800);
DISPLAY 0.553191 (3800 2800);
DISPLAY INVISIBLE (3800 2800);
FORCEPROP 1 LAST MATERIAL X6S
J 2
(3984 2829);
DISPLAY 0.574468 (3984 2829);
PAINT GREEN (3984 2829);
DISPLAY INVISIBLE (3984 2829);
FORCEPROP 2 LAST VOLTAGE 6.3V
J 2
(3625 2800);
DISPLAY 0.553191 (3625 2800);
DISPLAY INVISIBLE (3625 2800);
FORCEPROP 1 LAST PIN_NAMES_ROTATE TRUE
J 2
(3975 2750);
DISPLAY 0.489362 (3975 2750);
PAINT GREEN (3975 2750);
DISPLAY INVISIBLE (3975 2750);
FORCEPROP 2 LAST CDS_LIB pure_quanta
J 2
(3975 2750);
DISPLAY INVISIBLE (3975 2750);
FORCEPROP 1 LAST CDS_LMAN_SYM_OUTLINE -25,50,25,-50
J 2
(3975 2750);
DISPLAY 0.468085 (3975 2750);
PAINT GREEN (3975 2750);
DISPLAY INVISIBLE (3975 2750);
FORCEPROP 1 LAST PATH I156
J 2
(3975 2750);
DISPLAY 0.723404 (3975 2750);
DISPLAY INVISIBLE (3975 2750);
FORCEPROP 1 LAST $LOCATION C944
J 0
(4225 2825);
DISPLAY 1.021277 (4225 2825);
DISPLAY INVISIBLE (4225 2825);
FORCEPROP 2 LAST CDS_LOCATION C944
J 0
(4225 2825);
DISPLAY 1.021277 (4225 2825);
DISPLAY INVISIBLE (4225 2825);
FORCEPROP 2 LAST $SEC 1
J 2
(4150 2825);
DISPLAY 0.680851 (4150 2825);
PAINT MONO (4150 2825);
DISPLAY INVISIBLE (4150 2825);
FORCEPROP 2 LAST CDS_SEC 1
J 2
(4150 2825);
DISPLAY 0.680851 (4150 2825);
DISPLAY INVISIBLE (4150 2825);
FORCEADD Q_CAP_DIFFBUS..2
R 2
(3975 2900);
FORCEPROP 1 LAST PART_NUMBER SP_CH4221MEE01
J 2
(3859 2988);
DISPLAY 0.574468 (3859 2988);
PAINT GREEN (3859 2988);
DISPLAY INVISIBLE (3859 2988);
FORCEPROP 2 LAST VALUE DIFF BUS_0.22UF
J 2
(3825 2900);
DISPLAY 0.553191 (3825 2900);
FORCEPROP 1 LAST $LOCATION C943
J 2
(4209 2917);
DISPLAY 0.723404 (4209 2917);
PAINT GREEN (4209 2917);
FORCEPROP 2 LASTPIN (4050 2900) $PN 1
J 0
(4060 2910);
DISPLAY 0.808511 (4060 2910);
FORCEPROP 2 LASTPIN (3900 2900) $PN 2
J 2
(3890 2910);
DISPLAY 0.808511 (3890 2910);
FORCEPROP 2 LAST TOLERANCE 20%
J 2
(3900 2950);
DISPLAY 0.553191 (3900 2950);
DISPLAY INVISIBLE (3900 2950);
FORCEPROP 2 LAST PACK_TYPE C0201
J 2
(3800 2950);
DISPLAY 0.553191 (3800 2950);
DISPLAY INVISIBLE (3800 2950);
FORCEPROP 1 LAST MATERIAL X6S
J 2
(3984 2979);
DISPLAY 0.574468 (3984 2979);
PAINT GREEN (3984 2979);
DISPLAY INVISIBLE (3984 2979);
FORCEPROP 2 LAST VOLTAGE 6.3V
J 2
(3625 2950);
DISPLAY 0.553191 (3625 2950);
DISPLAY INVISIBLE (3625 2950);
FORCEPROP 1 LAST PIN_NAMES_ROTATE TRUE
J 2
(3975 2900);
DISPLAY 0.489362 (3975 2900);
PAINT GREEN (3975 2900);
DISPLAY INVISIBLE (3975 2900);
FORCEPROP 1 LAST CDS_LMAN_SYM_OUTLINE -25,50,25,-50
J 2
(3975 2900);
DISPLAY 0.468085 (3975 2900);
PAINT GREEN (3975 2900);
DISPLAY INVISIBLE (3975 2900);
FORCEPROP 2 LAST CDS_LIB pure_quanta
J 2
(3975 2900);
DISPLAY INVISIBLE (3975 2900);
FORCEPROP 1 LAST PATH I157
J 2
(3975 2900);
DISPLAY 0.723404 (3975 2900);
DISPLAY INVISIBLE (3975 2900);
FORCEPROP 1 LAST $LOCATION C943
J 0
(4225 2975);
DISPLAY 1.021277 (4225 2975);
DISPLAY INVISIBLE (4225 2975);
FORCEPROP 2 LAST CDS_LOCATION C943
J 0
(4225 2975);
DISPLAY 1.021277 (4225 2975);
DISPLAY INVISIBLE (4225 2975);
FORCEPROP 2 LAST $SEC 1
J 2
(4150 2975);
DISPLAY 0.680851 (4150 2975);
PAINT MONO (4150 2975);
DISPLAY INVISIBLE (4150 2975);
FORCEPROP 2 LAST CDS_SEC 1
J 2
(4150 2975);
DISPLAY 0.680851 (4150 2975);
DISPLAY INVISIBLE (4150 2975);
FORCEADD Q_CAP_DIFFBUS..2
R 2
(3975 2950);
FORCEPROP 1 LAST PART_NUMBER SP_CH4221MEE01
J 2
(3859 3038);
DISPLAY 0.574468 (3859 3038);
PAINT GREEN (3859 3038);
DISPLAY INVISIBLE (3859 3038);
FORCEPROP 2 LAST VALUE DIFF BUS_0.22UF
J 2
(3825 2950);
DISPLAY 0.553191 (3825 2950);
FORCEPROP 1 LAST $LOCATION C942
J 2
(4209 2967);
DISPLAY 0.723404 (4209 2967);
PAINT GREEN (4209 2967);
FORCEPROP 2 LASTPIN (4050 2950) $PN 1
J 0
(4060 2960);
DISPLAY 0.808511 (4060 2960);
FORCEPROP 2 LASTPIN (3900 2950) $PN 2
J 2
(3890 2960);
DISPLAY 0.808511 (3890 2960);
FORCEPROP 2 LAST TOLERANCE 20%
J 2
(3900 3000);
DISPLAY 0.553191 (3900 3000);
DISPLAY INVISIBLE (3900 3000);
FORCEPROP 2 LAST PACK_TYPE C0201
J 2
(3800 3000);
DISPLAY 0.553191 (3800 3000);
DISPLAY INVISIBLE (3800 3000);
FORCEPROP 1 LAST MATERIAL X6S
J 2
(3984 3029);
DISPLAY 0.574468 (3984 3029);
PAINT GREEN (3984 3029);
DISPLAY INVISIBLE (3984 3029);
FORCEPROP 2 LAST VOLTAGE 6.3V
J 2
(3625 3000);
DISPLAY 0.553191 (3625 3000);
DISPLAY INVISIBLE (3625 3000);
FORCEPROP 1 LAST PIN_NAMES_ROTATE TRUE
J 2
(3975 2950);
DISPLAY 0.489362 (3975 2950);
PAINT GREEN (3975 2950);
DISPLAY INVISIBLE (3975 2950);
FORCEPROP 1 LAST CDS_LMAN_SYM_OUTLINE -25,50,25,-50
J 2
(3975 2950);
DISPLAY 0.468085 (3975 2950);
PAINT GREEN (3975 2950);
DISPLAY INVISIBLE (3975 2950);
FORCEPROP 2 LAST CDS_LIB pure_quanta
J 2
(3975 2950);
DISPLAY INVISIBLE (3975 2950);
FORCEPROP 1 LAST PATH I158
J 2
(3975 2950);
DISPLAY 0.723404 (3975 2950);
DISPLAY INVISIBLE (3975 2950);
FORCEPROP 1 LAST $LOCATION C942
J 0
(4225 3025);
DISPLAY 1.021277 (4225 3025);
DISPLAY INVISIBLE (4225 3025);
FORCEPROP 2 LAST CDS_LOCATION C942
J 0
(4225 3025);
DISPLAY 1.021277 (4225 3025);
DISPLAY INVISIBLE (4225 3025);
FORCEPROP 2 LAST $SEC 1
J 2
(4150 3025);
DISPLAY 0.680851 (4150 3025);
PAINT MONO (4150 3025);
DISPLAY INVISIBLE (4150 3025);
FORCEPROP 2 LAST CDS_SEC 1
J 2
(4150 3025);
DISPLAY 0.680851 (4150 3025);
DISPLAY INVISIBLE (4150 3025);
FORCEADD Q_CAP_DIFFBUS..2
R 2
(3975 3100);
FORCEPROP 1 LAST PART_NUMBER SP_CH4221MEE01
J 2
(3859 3188);
DISPLAY 0.574468 (3859 3188);
PAINT GREEN (3859 3188);
DISPLAY INVISIBLE (3859 3188);
FORCEPROP 2 LAST VALUE DIFF BUS_0.22UF
J 2
(3825 3100);
DISPLAY 0.553191 (3825 3100);
FORCEPROP 1 LAST $LOCATION C941
J 2
(4209 3117);
DISPLAY 0.723404 (4209 3117);
PAINT GREEN (4209 3117);
FORCEPROP 2 LASTPIN (4050 3100) $PN 1
J 0
(4060 3110);
DISPLAY 0.808511 (4060 3110);
FORCEPROP 2 LASTPIN (3900 3100) $PN 2
J 2
(3890 3110);
DISPLAY 0.808511 (3890 3110);
FORCEPROP 2 LAST TOLERANCE 20%
J 2
(3900 3150);
DISPLAY 0.553191 (3900 3150);
DISPLAY INVISIBLE (3900 3150);
FORCEPROP 2 LAST PACK_TYPE C0201
J 2
(3800 3150);
DISPLAY 0.553191 (3800 3150);
DISPLAY INVISIBLE (3800 3150);
FORCEPROP 1 LAST MATERIAL X6S
J 2
(3984 3179);
DISPLAY 0.574468 (3984 3179);
PAINT GREEN (3984 3179);
DISPLAY INVISIBLE (3984 3179);
FORCEPROP 2 LAST VOLTAGE 6.3V
J 2
(3625 3150);
DISPLAY 0.553191 (3625 3150);
DISPLAY INVISIBLE (3625 3150);
FORCEPROP 1 LAST PIN_NAMES_ROTATE TRUE
J 2
(3975 3100);
DISPLAY 0.489362 (3975 3100);
PAINT GREEN (3975 3100);
DISPLAY INVISIBLE (3975 3100);
FORCEPROP 2 LAST CDS_LIB pure_quanta
J 2
(3975 3100);
DISPLAY INVISIBLE (3975 3100);
FORCEPROP 1 LAST CDS_LMAN_SYM_OUTLINE -25,50,25,-50
J 2
(3975 3100);
DISPLAY 0.468085 (3975 3100);
PAINT GREEN (3975 3100);
DISPLAY INVISIBLE (3975 3100);
FORCEPROP 1 LAST PATH I159
J 2
(3975 3100);
DISPLAY 0.723404 (3975 3100);
DISPLAY INVISIBLE (3975 3100);
FORCEPROP 1 LAST $LOCATION C941
J 0
(4225 3175);
DISPLAY 1.021277 (4225 3175);
DISPLAY INVISIBLE (4225 3175);
FORCEPROP 2 LAST CDS_LOCATION C941
J 0
(4225 3175);
DISPLAY 1.021277 (4225 3175);
DISPLAY INVISIBLE (4225 3175);
FORCEPROP 2 LAST $SEC 1
J 2
(4150 3175);
DISPLAY 0.680851 (4150 3175);
PAINT MONO (4150 3175);
DISPLAY INVISIBLE (4150 3175);
FORCEPROP 2 LAST CDS_SEC 1
J 2
(4150 3175);
DISPLAY 0.680851 (4150 3175);
DISPLAY INVISIBLE (4150 3175);
FORCEADD TAP..1
R 2
(-1300 1175);
FORCEPROP 3 LASTPIN (-1250 1175) SIG_NAME P5E_CPU0_PE0_TX_DN<4>
J 0
(-1240 1185);
DISPLAY 0.659574 (-1240 1185);
PAINT MONO (-1240 1185);
DISPLAY INVISIBLE (-1240 1185);
FORCEPROP 1 LASTPIN (-1250 1175) BN 4
J 2
(-1238 1183);
DISPLAY 0.680851 (-1238 1183);
PAINT GREEN (-1238 1183);
FORCEPROP 2 LAST CDS_LIB standard
J 0
(-1300 1175);
DISPLAY INVISIBLE (-1300 1175);
FORCEPROP 1 LAST BODY_TYPE PLUMBING
J 2
(-1300 1225);
DISPLAY 0.872340 (-1300 1225);
PAINT GREEN (-1300 1225);
DISPLAY INVISIBLE (-1300 1225);
FORCEPROP 1 LAST HDL_TAP TRUE
J 2
(-1625 1050);
DISPLAY 0.872340 (-1625 1050);
DISPLAY INVISIBLE (-1625 1050);
FORCEPROP 1 LAST PATH I16
J 2
(-1298 1175);
DISPLAY 0.872340 (-1298 1175);
PAINT GREEN (-1298 1175);
DISPLAY INVISIBLE (-1298 1175);
FORCEADD Q_CAP_DIFFBUS..2
R 2
(3975 3150);
FORCEPROP 1 LAST PART_NUMBER SP_CH4221MEE01
J 2
(3859 3238);
DISPLAY 0.574468 (3859 3238);
PAINT GREEN (3859 3238);
DISPLAY INVISIBLE (3859 3238);
FORCEPROP 2 LAST VALUE DIFF BUS_0.22UF
J 2
(3825 3150);
DISPLAY 0.553191 (3825 3150);
FORCEPROP 1 LAST $LOCATION C940
J 2
(4209 3167);
DISPLAY 0.723404 (4209 3167);
PAINT GREEN (4209 3167);
FORCEPROP 2 LASTPIN (4050 3150) $PN 1
J 0
(4060 3160);
DISPLAY 0.808511 (4060 3160);
FORCEPROP 2 LASTPIN (3900 3150) $PN 2
J 2
(3890 3160);
DISPLAY 0.808511 (3890 3160);
FORCEPROP 2 LAST TOLERANCE 20%
J 2
(3900 3200);
DISPLAY 0.553191 (3900 3200);
DISPLAY INVISIBLE (3900 3200);
FORCEPROP 2 LAST PACK_TYPE C0201
J 2
(3800 3200);
DISPLAY 0.553191 (3800 3200);
DISPLAY INVISIBLE (3800 3200);
FORCEPROP 1 LAST MATERIAL X6S
J 2
(3984 3229);
DISPLAY 0.574468 (3984 3229);
PAINT GREEN (3984 3229);
DISPLAY INVISIBLE (3984 3229);
FORCEPROP 2 LAST VOLTAGE 6.3V
J 2
(3625 3200);
DISPLAY 0.553191 (3625 3200);
DISPLAY INVISIBLE (3625 3200);
FORCEPROP 1 LAST PIN_NAMES_ROTATE TRUE
J 2
(3975 3150);
DISPLAY 0.489362 (3975 3150);
PAINT GREEN (3975 3150);
DISPLAY INVISIBLE (3975 3150);
FORCEPROP 2 LAST CDS_LIB pure_quanta
J 2
(3975 3150);
DISPLAY INVISIBLE (3975 3150);
FORCEPROP 1 LAST CDS_LMAN_SYM_OUTLINE -25,50,25,-50
J 2
(3975 3150);
DISPLAY 0.468085 (3975 3150);
PAINT GREEN (3975 3150);
DISPLAY INVISIBLE (3975 3150);
FORCEPROP 1 LAST PATH I160
J 2
(3975 3150);
DISPLAY 0.723404 (3975 3150);
DISPLAY INVISIBLE (3975 3150);
FORCEPROP 1 LAST $LOCATION C940
J 0
(4225 3225);
DISPLAY 1.021277 (4225 3225);
DISPLAY INVISIBLE (4225 3225);
FORCEPROP 2 LAST CDS_LOCATION C940
J 0
(4225 3225);
DISPLAY 1.021277 (4225 3225);
DISPLAY INVISIBLE (4225 3225);
FORCEPROP 2 LAST $SEC 1
J 2
(4150 3225);
DISPLAY 0.680851 (4150 3225);
PAINT MONO (4150 3225);
DISPLAY INVISIBLE (4150 3225);
FORCEPROP 2 LAST CDS_SEC 1
J 2
(4150 3225);
DISPLAY 0.680851 (4150 3225);
DISPLAY INVISIBLE (4150 3225);
FORCEADD TAP..1
R 2
(3250 3350);
FORCEPROP 3 LASTPIN (3300 3350) SIG_NAME P5E_CPU0_PE2_TX_DN<13>
J 0
(3310 3360);
DISPLAY 0.659574 (3310 3360);
PAINT MONO (3310 3360);
DISPLAY INVISIBLE (3310 3360);
FORCEPROP 1 LASTPIN (3300 3350) BN 13
J 2
(3312 3358);
DISPLAY 0.680851 (3312 3358);
PAINT GREEN (3312 3358);
FORCEPROP 2 LAST CDS_LIB standard
J 0
(3250 3350);
DISPLAY INVISIBLE (3250 3350);
FORCEPROP 1 LAST BODY_TYPE PLUMBING
J 2
(3250 3400);
DISPLAY 0.872340 (3250 3400);
PAINT GREEN (3250 3400);
DISPLAY INVISIBLE (3250 3400);
FORCEPROP 1 LAST HDL_TAP TRUE
J 2
(2925 3225);
DISPLAY 0.872340 (2925 3225);
DISPLAY INVISIBLE (2925 3225);
FORCEPROP 1 LAST PATH I161
J 2
(3252 3350);
DISPLAY 0.872340 (3252 3350);
PAINT GREEN (3252 3350);
DISPLAY INVISIBLE (3252 3350);
FORCEADD TAP..1
R 2
(3250 3550);
FORCEPROP 3 LASTPIN (3300 3550) SIG_NAME P5E_CPU0_PE2_TX_DN<14>
J 0
(3310 3560);
DISPLAY 0.659574 (3310 3560);
PAINT MONO (3310 3560);
DISPLAY INVISIBLE (3310 3560);
FORCEPROP 1 LASTPIN (3300 3550) BN 14
J 2
(3312 3558);
DISPLAY 0.680851 (3312 3558);
PAINT GREEN (3312 3558);
FORCEPROP 2 LAST CDS_LIB standard
J 0
(3250 3550);
DISPLAY INVISIBLE (3250 3550);
FORCEPROP 1 LAST BODY_TYPE PLUMBING
J 2
(3250 3600);
DISPLAY 0.872340 (3250 3600);
PAINT GREEN (3250 3600);
DISPLAY INVISIBLE (3250 3600);
FORCEPROP 1 LAST HDL_TAP TRUE
J 2
(2925 3425);
DISPLAY 0.872340 (2925 3425);
DISPLAY INVISIBLE (2925 3425);
FORCEPROP 1 LAST PATH I162
J 2
(3252 3550);
DISPLAY 0.872340 (3252 3550);
PAINT GREEN (3252 3550);
DISPLAY INVISIBLE (3252 3550);
FORCEADD TAP..1
R 2
(3250 3750);
FORCEPROP 3 LASTPIN (3300 3750) SIG_NAME P5E_CPU0_PE2_TX_DN<15>
J 0
(3310 3760);
DISPLAY 0.659574 (3310 3760);
PAINT MONO (3310 3760);
DISPLAY INVISIBLE (3310 3760);
FORCEPROP 1 LASTPIN (3300 3750) BN 15
J 2
(3312 3758);
DISPLAY 0.680851 (3312 3758);
PAINT GREEN (3312 3758);
FORCEPROP 2 LAST CDS_LIB standard
J 0
(3250 3750);
DISPLAY INVISIBLE (3250 3750);
FORCEPROP 1 LAST BODY_TYPE PLUMBING
J 2
(3250 3800);
DISPLAY 0.872340 (3250 3800);
PAINT GREEN (3250 3800);
DISPLAY INVISIBLE (3250 3800);
FORCEPROP 1 LAST HDL_TAP TRUE
J 2
(2925 3625);
DISPLAY 0.872340 (2925 3625);
DISPLAY INVISIBLE (2925 3625);
FORCEPROP 1 LAST PATH I163
J 2
(3252 3750);
DISPLAY 0.872340 (3252 3750);
PAINT GREEN (3252 3750);
DISPLAY INVISIBLE (3252 3750);
FORCEADD Q_CAP_DIFFBUS..2
R 2
(3975 3300);
FORCEPROP 1 LAST PART_NUMBER SP_CH4221MEE01
J 2
(3859 3388);
DISPLAY 0.574468 (3859 3388);
PAINT GREEN (3859 3388);
DISPLAY INVISIBLE (3859 3388);
FORCEPROP 2 LAST VALUE DIFF BUS_0.22UF
J 2
(3825 3300);
DISPLAY 0.553191 (3825 3300);
FORCEPROP 1 LAST $LOCATION C939
J 2
(4209 3317);
DISPLAY 0.723404 (4209 3317);
PAINT GREEN (4209 3317);
FORCEPROP 2 LASTPIN (4050 3300) $PN 1
J 0
(4060 3310);
DISPLAY 0.808511 (4060 3310);
FORCEPROP 2 LASTPIN (3900 3300) $PN 2
J 2
(3890 3310);
DISPLAY 0.808511 (3890 3310);
FORCEPROP 2 LAST TOLERANCE 20%
J 2
(3900 3350);
DISPLAY 0.553191 (3900 3350);
DISPLAY INVISIBLE (3900 3350);
FORCEPROP 2 LAST PACK_TYPE C0201
J 2
(3800 3350);
DISPLAY 0.553191 (3800 3350);
DISPLAY INVISIBLE (3800 3350);
FORCEPROP 1 LAST MATERIAL X6S
J 2
(3984 3379);
DISPLAY 0.574468 (3984 3379);
PAINT GREEN (3984 3379);
DISPLAY INVISIBLE (3984 3379);
FORCEPROP 2 LAST VOLTAGE 6.3V
J 2
(3625 3350);
DISPLAY 0.553191 (3625 3350);
DISPLAY INVISIBLE (3625 3350);
FORCEPROP 1 LAST PIN_NAMES_ROTATE TRUE
J 2
(3975 3300);
DISPLAY 0.489362 (3975 3300);
PAINT GREEN (3975 3300);
DISPLAY INVISIBLE (3975 3300);
FORCEPROP 2 LAST CDS_LIB pure_quanta
J 2
(3975 3300);
DISPLAY INVISIBLE (3975 3300);
FORCEPROP 1 LAST CDS_LMAN_SYM_OUTLINE -25,50,25,-50
J 2
(3975 3300);
DISPLAY 0.468085 (3975 3300);
PAINT GREEN (3975 3300);
DISPLAY INVISIBLE (3975 3300);
FORCEPROP 1 LAST PATH I164
J 2
(3975 3300);
DISPLAY 0.723404 (3975 3300);
DISPLAY INVISIBLE (3975 3300);
FORCEPROP 1 LAST $LOCATION C939
J 0
(4225 3375);
DISPLAY 1.021277 (4225 3375);
DISPLAY INVISIBLE (4225 3375);
FORCEPROP 2 LAST CDS_LOCATION C939
J 0
(4225 3375);
DISPLAY 1.021277 (4225 3375);
DISPLAY INVISIBLE (4225 3375);
FORCEPROP 2 LAST $SEC 1
J 2
(4150 3375);
DISPLAY 0.680851 (4150 3375);
PAINT MONO (4150 3375);
DISPLAY INVISIBLE (4150 3375);
FORCEPROP 2 LAST CDS_SEC 1
J 2
(4150 3375);
DISPLAY 0.680851 (4150 3375);
DISPLAY INVISIBLE (4150 3375);
FORCEADD Q_CAP_DIFFBUS..2
R 2
(3975 3350);
FORCEPROP 1 LAST PART_NUMBER SP_CH4221MEE01
J 2
(3859 3438);
DISPLAY 0.574468 (3859 3438);
PAINT GREEN (3859 3438);
DISPLAY INVISIBLE (3859 3438);
FORCEPROP 2 LAST VALUE DIFF BUS_0.22UF
J 2
(3825 3350);
DISPLAY 0.553191 (3825 3350);
FORCEPROP 1 LAST $LOCATION C938
J 2
(4209 3367);
DISPLAY 0.723404 (4209 3367);
PAINT GREEN (4209 3367);
FORCEPROP 2 LASTPIN (4050 3350) $PN 1
J 0
(4060 3360);
DISPLAY 0.808511 (4060 3360);
FORCEPROP 2 LASTPIN (3900 3350) $PN 2
J 2
(3890 3360);
DISPLAY 0.808511 (3890 3360);
FORCEPROP 2 LAST TOLERANCE 20%
J 2
(3900 3400);
DISPLAY 0.553191 (3900 3400);
DISPLAY INVISIBLE (3900 3400);
FORCEPROP 2 LAST PACK_TYPE C0201
J 2
(3800 3400);
DISPLAY 0.553191 (3800 3400);
DISPLAY INVISIBLE (3800 3400);
FORCEPROP 1 LAST MATERIAL X6S
J 2
(3984 3429);
DISPLAY 0.574468 (3984 3429);
PAINT GREEN (3984 3429);
DISPLAY INVISIBLE (3984 3429);
FORCEPROP 2 LAST VOLTAGE 6.3V
J 2
(3625 3400);
DISPLAY 0.553191 (3625 3400);
DISPLAY INVISIBLE (3625 3400);
FORCEPROP 1 LAST PIN_NAMES_ROTATE TRUE
J 2
(3975 3350);
DISPLAY 0.489362 (3975 3350);
PAINT GREEN (3975 3350);
DISPLAY INVISIBLE (3975 3350);
FORCEPROP 2 LAST CDS_LIB pure_quanta
J 2
(3975 3350);
DISPLAY INVISIBLE (3975 3350);
FORCEPROP 1 LAST CDS_LMAN_SYM_OUTLINE -25,50,25,-50
J 2
(3975 3350);
DISPLAY 0.468085 (3975 3350);
PAINT GREEN (3975 3350);
DISPLAY INVISIBLE (3975 3350);
FORCEPROP 1 LAST PATH I165
J 2
(3975 3350);
DISPLAY 0.723404 (3975 3350);
DISPLAY INVISIBLE (3975 3350);
FORCEPROP 1 LAST $LOCATION C938
J 0
(4225 3425);
DISPLAY 1.021277 (4225 3425);
DISPLAY INVISIBLE (4225 3425);
FORCEPROP 2 LAST CDS_LOCATION C938
J 0
(4225 3425);
DISPLAY 1.021277 (4225 3425);
DISPLAY INVISIBLE (4225 3425);
FORCEPROP 2 LAST $SEC 1
J 2
(4150 3425);
DISPLAY 0.680851 (4150 3425);
PAINT MONO (4150 3425);
DISPLAY INVISIBLE (4150 3425);
FORCEPROP 2 LAST CDS_SEC 1
J 2
(4150 3425);
DISPLAY 0.680851 (4150 3425);
DISPLAY INVISIBLE (4150 3425);
FORCEADD Q_CAP_DIFFBUS..2
R 2
(3975 3500);
FORCEPROP 1 LAST PART_NUMBER SP_CH4221MEE01
J 2
(3859 3588);
DISPLAY 0.574468 (3859 3588);
PAINT GREEN (3859 3588);
DISPLAY INVISIBLE (3859 3588);
FORCEPROP 2 LAST VALUE DIFF BUS_0.22UF
J 2
(3825 3500);
DISPLAY 0.553191 (3825 3500);
FORCEPROP 1 LAST $LOCATION C937
J 2
(4209 3517);
DISPLAY 0.723404 (4209 3517);
PAINT GREEN (4209 3517);
FORCEPROP 2 LASTPIN (4050 3500) $PN 1
J 0
(4060 3510);
DISPLAY 0.808511 (4060 3510);
FORCEPROP 2 LASTPIN (3900 3500) $PN 2
J 2
(3890 3510);
DISPLAY 0.808511 (3890 3510);
FORCEPROP 2 LAST TOLERANCE 20%
J 2
(3900 3550);
DISPLAY 0.553191 (3900 3550);
DISPLAY INVISIBLE (3900 3550);
FORCEPROP 2 LAST PACK_TYPE C0201
J 2
(3800 3550);
DISPLAY 0.553191 (3800 3550);
DISPLAY INVISIBLE (3800 3550);
FORCEPROP 1 LAST MATERIAL X6S
J 2
(3984 3579);
DISPLAY 0.574468 (3984 3579);
PAINT GREEN (3984 3579);
DISPLAY INVISIBLE (3984 3579);
FORCEPROP 2 LAST VOLTAGE 6.3V
J 2
(3625 3550);
DISPLAY 0.553191 (3625 3550);
DISPLAY INVISIBLE (3625 3550);
FORCEPROP 1 LAST PIN_NAMES_ROTATE TRUE
J 2
(3975 3500);
DISPLAY 0.489362 (3975 3500);
PAINT GREEN (3975 3500);
DISPLAY INVISIBLE (3975 3500);
FORCEPROP 2 LAST CDS_LIB pure_quanta
J 2
(3975 3500);
DISPLAY INVISIBLE (3975 3500);
FORCEPROP 1 LAST CDS_LMAN_SYM_OUTLINE -25,50,25,-50
J 2
(3975 3500);
DISPLAY 0.468085 (3975 3500);
PAINT GREEN (3975 3500);
DISPLAY INVISIBLE (3975 3500);
FORCEPROP 1 LAST PATH I166
J 2
(3975 3500);
DISPLAY 0.723404 (3975 3500);
DISPLAY INVISIBLE (3975 3500);
FORCEPROP 1 LAST $LOCATION C937
J 0
(4225 3575);
DISPLAY 1.021277 (4225 3575);
DISPLAY INVISIBLE (4225 3575);
FORCEPROP 2 LAST CDS_LOCATION C937
J 0
(4225 3575);
DISPLAY 1.021277 (4225 3575);
DISPLAY INVISIBLE (4225 3575);
FORCEPROP 2 LAST $SEC 1
J 2
(4150 3575);
DISPLAY 0.680851 (4150 3575);
PAINT MONO (4150 3575);
DISPLAY INVISIBLE (4150 3575);
FORCEPROP 2 LAST CDS_SEC 1
J 2
(4150 3575);
DISPLAY 0.680851 (4150 3575);
DISPLAY INVISIBLE (4150 3575);
FORCEADD Q_CAP_DIFFBUS..2
R 2
(3975 3550);
FORCEPROP 1 LAST PART_NUMBER SP_CH4221MEE01
J 2
(3859 3638);
DISPLAY 0.574468 (3859 3638);
PAINT GREEN (3859 3638);
DISPLAY INVISIBLE (3859 3638);
FORCEPROP 2 LAST VALUE DIFF BUS_0.22UF
J 2
(3825 3550);
DISPLAY 0.553191 (3825 3550);
FORCEPROP 1 LAST $LOCATION C936
J 2
(4209 3567);
DISPLAY 0.723404 (4209 3567);
PAINT GREEN (4209 3567);
FORCEPROP 2 LASTPIN (4050 3550) $PN 1
J 0
(4060 3560);
DISPLAY 0.808511 (4060 3560);
FORCEPROP 2 LASTPIN (3900 3550) $PN 2
J 2
(3890 3560);
DISPLAY 0.808511 (3890 3560);
FORCEPROP 2 LAST TOLERANCE 20%
J 2
(3900 3600);
DISPLAY 0.553191 (3900 3600);
DISPLAY INVISIBLE (3900 3600);
FORCEPROP 2 LAST PACK_TYPE C0201
J 2
(3800 3600);
DISPLAY 0.553191 (3800 3600);
DISPLAY INVISIBLE (3800 3600);
FORCEPROP 1 LAST MATERIAL X6S
J 2
(3984 3629);
DISPLAY 0.574468 (3984 3629);
PAINT GREEN (3984 3629);
DISPLAY INVISIBLE (3984 3629);
FORCEPROP 2 LAST VOLTAGE 6.3V
J 2
(3625 3600);
DISPLAY 0.553191 (3625 3600);
DISPLAY INVISIBLE (3625 3600);
FORCEPROP 1 LAST PIN_NAMES_ROTATE TRUE
J 2
(3975 3550);
DISPLAY 0.489362 (3975 3550);
PAINT GREEN (3975 3550);
DISPLAY INVISIBLE (3975 3550);
FORCEPROP 2 LAST CDS_LIB pure_quanta
J 2
(3975 3550);
DISPLAY INVISIBLE (3975 3550);
FORCEPROP 1 LAST CDS_LMAN_SYM_OUTLINE -25,50,25,-50
J 2
(3975 3550);
DISPLAY 0.468085 (3975 3550);
PAINT GREEN (3975 3550);
DISPLAY INVISIBLE (3975 3550);
FORCEPROP 1 LAST PATH I167
J 2
(3975 3550);
DISPLAY 0.723404 (3975 3550);
DISPLAY INVISIBLE (3975 3550);
FORCEPROP 1 LAST $LOCATION C936
J 0
(4225 3625);
DISPLAY 1.021277 (4225 3625);
DISPLAY INVISIBLE (4225 3625);
FORCEPROP 2 LAST CDS_LOCATION C936
J 0
(4225 3625);
DISPLAY 1.021277 (4225 3625);
DISPLAY INVISIBLE (4225 3625);
FORCEPROP 2 LAST $SEC 1
J 2
(4150 3625);
DISPLAY 0.680851 (4150 3625);
PAINT MONO (4150 3625);
DISPLAY INVISIBLE (4150 3625);
FORCEPROP 2 LAST CDS_SEC 1
J 2
(4150 3625);
DISPLAY 0.680851 (4150 3625);
DISPLAY INVISIBLE (4150 3625);
FORCEADD Q_CAP_DIFFBUS..2
R 2
(3975 3700);
FORCEPROP 1 LAST PART_NUMBER SP_CH4221MEE01
J 2
(3859 3788);
DISPLAY 0.574468 (3859 3788);
PAINT GREEN (3859 3788);
DISPLAY INVISIBLE (3859 3788);
FORCEPROP 2 LAST VALUE DIFF BUS_0.22UF
J 2
(3825 3700);
DISPLAY 0.553191 (3825 3700);
FORCEPROP 1 LAST $LOCATION C935
J 2
(4209 3717);
DISPLAY 0.723404 (4209 3717);
PAINT GREEN (4209 3717);
FORCEPROP 2 LASTPIN (4050 3700) $PN 1
J 0
(4060 3710);
DISPLAY 0.808511 (4060 3710);
FORCEPROP 2 LASTPIN (3900 3700) $PN 2
J 2
(3890 3710);
DISPLAY 0.808511 (3890 3710);
FORCEPROP 2 LAST TOLERANCE 20%
J 2
(3900 3750);
DISPLAY 0.553191 (3900 3750);
DISPLAY INVISIBLE (3900 3750);
FORCEPROP 2 LAST PACK_TYPE C0201
J 2
(3800 3750);
DISPLAY 0.553191 (3800 3750);
DISPLAY INVISIBLE (3800 3750);
FORCEPROP 1 LAST MATERIAL X6S
J 2
(3984 3779);
DISPLAY 0.574468 (3984 3779);
PAINT GREEN (3984 3779);
DISPLAY INVISIBLE (3984 3779);
FORCEPROP 2 LAST VOLTAGE 6.3V
J 2
(3625 3750);
DISPLAY 0.553191 (3625 3750);
DISPLAY INVISIBLE (3625 3750);
FORCEPROP 1 LAST PIN_NAMES_ROTATE TRUE
J 2
(3975 3700);
DISPLAY 0.489362 (3975 3700);
PAINT GREEN (3975 3700);
DISPLAY INVISIBLE (3975 3700);
FORCEPROP 2 LAST CDS_LIB pure_quanta
J 2
(3975 3700);
DISPLAY INVISIBLE (3975 3700);
FORCEPROP 1 LAST CDS_LMAN_SYM_OUTLINE -25,50,25,-50
J 2
(3975 3700);
DISPLAY 0.468085 (3975 3700);
PAINT GREEN (3975 3700);
DISPLAY INVISIBLE (3975 3700);
FORCEPROP 1 LAST PATH I168
J 2
(3975 3700);
DISPLAY 0.723404 (3975 3700);
DISPLAY INVISIBLE (3975 3700);
FORCEPROP 1 LAST $LOCATION C935
J 0
(4225 3775);
DISPLAY 1.021277 (4225 3775);
DISPLAY INVISIBLE (4225 3775);
FORCEPROP 2 LAST CDS_LOCATION C935
J 0
(4225 3775);
DISPLAY 1.021277 (4225 3775);
DISPLAY INVISIBLE (4225 3775);
FORCEPROP 2 LAST $SEC 1
J 2
(4150 3775);
DISPLAY 0.680851 (4150 3775);
PAINT MONO (4150 3775);
DISPLAY INVISIBLE (4150 3775);
FORCEPROP 2 LAST CDS_SEC 1
J 2
(4150 3775);
DISPLAY 0.680851 (4150 3775);
DISPLAY INVISIBLE (4150 3775);
FORCEADD Q_CAP_DIFFBUS..2
R 2
(3975 3750);
FORCEPROP 1 LAST PART_NUMBER SP_CH4221MEE01
J 2
(4234 3838);
DISPLAY 0.574468 (4234 3838);
PAINT GREEN (4234 3838);
DISPLAY INVISIBLE (4234 3838);
FORCEPROP 2 LAST PACK_TYPE C0201
J 2
(3975 3900);
DISPLAY 0.553191 (3975 3900);
PAINT GREEN (3975 3900);
FORCEPROP 2 LAST TOLERANCE 20%
J 2
(4075 3900);
DISPLAY 0.553191 (4075 3900);
PAINT GREEN (4075 3900);
FORCEPROP 2 LAST VOLTAGE 6.3V
J 2
(4225 3900);
DISPLAY 0.553191 (4225 3900);
PAINT GREEN (4225 3900);
FORCEPROP 2 LAST VALUE DIFF BUS_0.22UF
J 2
(3825 3750);
DISPLAY 0.553191 (3825 3750);
FORCEPROP 1 LAST MATERIAL X6S
J 2
(3934 3954);
DISPLAY 0.574468 (3934 3954);
PAINT GREEN (3934 3954);
FORCEPROP 1 LAST $LOCATION C934
J 2
(4209 3767);
DISPLAY 0.723404 (4209 3767);
PAINT GREEN (4209 3767);
FORCEPROP 2 LASTPIN (4050 3750) $PN 1
J 0
(4060 3760);
DISPLAY 0.808511 (4060 3760);
FORCEPROP 2 LASTPIN (3900 3750) $PN 2
J 2
(3890 3760);
DISPLAY 0.808511 (3890 3760);
FORCEPROP 1 LAST PIN_NAMES_ROTATE TRUE
J 2
(3975 3750);
DISPLAY 0.489362 (3975 3750);
PAINT GREEN (3975 3750);
DISPLAY INVISIBLE (3975 3750);
FORCEPROP 1 LAST CDS_LMAN_SYM_OUTLINE -25,50,25,-50
J 2
(3975 3750);
DISPLAY 0.468085 (3975 3750);
PAINT GREEN (3975 3750);
DISPLAY INVISIBLE (3975 3750);
FORCEPROP 2 LAST CDS_LIB pure_quanta
J 2
(3975 3750);
DISPLAY INVISIBLE (3975 3750);
FORCEPROP 1 LAST PATH I169
J 2
(3975 3750);
DISPLAY 0.723404 (3975 3750);
DISPLAY INVISIBLE (3975 3750);
FORCEPROP 1 LAST $LOCATION C934
J 0
(4225 3825);
DISPLAY 1.021277 (4225 3825);
DISPLAY INVISIBLE (4225 3825);
FORCEPROP 2 LAST CDS_LOCATION C934
J 0
(3950 4000);
DISPLAY 1.021277 (3950 4000);
DISPLAY INVISIBLE (3950 4000);
FORCEPROP 2 LAST $SEC 1
J 2
(4150 3825);
DISPLAY 0.680851 (4150 3825);
PAINT MONO (4150 3825);
DISPLAY INVISIBLE (4150 3825);
FORCEPROP 2 LAST CDS_SEC 1
J 2
(4150 3825);
DISPLAY 0.680851 (4150 3825);
DISPLAY INVISIBLE (4150 3825);
FORCEADD TAP..1
R 2
(-1300 1375);
FORCEPROP 3 LASTPIN (-1250 1375) SIG_NAME P5E_CPU0_PE0_TX_DN<5>
J 0
(-1240 1385);
DISPLAY 0.659574 (-1240 1385);
PAINT MONO (-1240 1385);
DISPLAY INVISIBLE (-1240 1385);
FORCEPROP 1 LASTPIN (-1250 1375) BN 5
J 2
(-1238 1383);
DISPLAY 0.680851 (-1238 1383);
PAINT GREEN (-1238 1383);
FORCEPROP 2 LAST CDS_LIB standard
J 0
(-1300 1375);
DISPLAY INVISIBLE (-1300 1375);
FORCEPROP 1 LAST BODY_TYPE PLUMBING
J 2
(-1300 1425);
DISPLAY 0.872340 (-1300 1425);
PAINT GREEN (-1300 1425);
DISPLAY INVISIBLE (-1300 1425);
FORCEPROP 1 LAST HDL_TAP TRUE
J 2
(-1625 1250);
DISPLAY 0.872340 (-1625 1250);
DISPLAY INVISIBLE (-1625 1250);
FORCEPROP 1 LAST PATH I17
J 2
(-1298 1375);
DISPLAY 0.872340 (-1298 1375);
PAINT GREEN (-1298 1375);
DISPLAY INVISIBLE (-1298 1375);
FORCEADD TAP..1
(4525 575);
FORCEPROP 3 LASTPIN (4475 575) SIG_NAME P5E_CPU0_PE2_TX_C_DN<1>
J 0
(4485 585);
DISPLAY 0.659574 (4485 585);
PAINT MONO (4485 585);
DISPLAY INVISIBLE (4485 585);
FORCEPROP 1 LASTPIN (4475 575) BN 1
J 0
(4463 583);
DISPLAY 0.680851 (4463 583);
PAINT GREEN (4463 583);
FORCEPROP 2 LAST CDS_LIB standard
J 0
(4525 575);
DISPLAY INVISIBLE (4525 575);
FORCEPROP 1 LAST BODY_TYPE PLUMBING
J 0
(4525 625);
DISPLAY 0.872340 (4525 625);
PAINT GREEN (4525 625);
DISPLAY INVISIBLE (4525 625);
FORCEPROP 1 LAST HDL_TAP TRUE
J 0
(4850 450);
DISPLAY 0.872340 (4850 450);
DISPLAY INVISIBLE (4850 450);
FORCEPROP 1 LAST PATH I170
J 0
(4523 575);
DISPLAY 0.872340 (4523 575);
PAINT GREEN (4523 575);
DISPLAY INVISIBLE (4523 575);
FORCEADD TAP..1
(4525 775);
FORCEPROP 3 LASTPIN (4475 775) SIG_NAME P5E_CPU0_PE2_TX_C_DN<2>
J 0
(4485 785);
DISPLAY 0.659574 (4485 785);
PAINT MONO (4485 785);
DISPLAY INVISIBLE (4485 785);
FORCEPROP 1 LASTPIN (4475 775) BN 2
J 0
(4463 783);
DISPLAY 0.680851 (4463 783);
PAINT GREEN (4463 783);
FORCEPROP 2 LAST CDS_LIB standard
J 0
(4525 775);
DISPLAY INVISIBLE (4525 775);
FORCEPROP 1 LAST BODY_TYPE PLUMBING
J 0
(4525 825);
DISPLAY 0.872340 (4525 825);
PAINT GREEN (4525 825);
DISPLAY INVISIBLE (4525 825);
FORCEPROP 1 LAST HDL_TAP TRUE
J 0
(4850 650);
DISPLAY 0.872340 (4850 650);
DISPLAY INVISIBLE (4850 650);
FORCEPROP 1 LAST PATH I171
J 0
(4523 775);
DISPLAY 0.872340 (4523 775);
PAINT GREEN (4523 775);
DISPLAY INVISIBLE (4523 775);
FORCEADD TAP..1
(4525 975);
FORCEPROP 3 LASTPIN (4475 975) SIG_NAME P5E_CPU0_PE2_TX_C_DN<3>
J 0
(4485 985);
DISPLAY 0.659574 (4485 985);
PAINT MONO (4485 985);
DISPLAY INVISIBLE (4485 985);
FORCEPROP 1 LASTPIN (4475 975) BN 3
J 0
(4463 983);
DISPLAY 0.680851 (4463 983);
PAINT GREEN (4463 983);
FORCEPROP 2 LAST CDS_LIB standard
J 0
(4525 975);
DISPLAY INVISIBLE (4525 975);
FORCEPROP 1 LAST BODY_TYPE PLUMBING
J 0
(4525 1025);
DISPLAY 0.872340 (4525 1025);
PAINT GREEN (4525 1025);
DISPLAY INVISIBLE (4525 1025);
FORCEPROP 1 LAST HDL_TAP TRUE
J 0
(4850 850);
DISPLAY 0.872340 (4850 850);
DISPLAY INVISIBLE (4850 850);
FORCEPROP 1 LAST PATH I172
J 0
(4523 975);
DISPLAY 0.872340 (4523 975);
PAINT GREEN (4523 975);
DISPLAY INVISIBLE (4523 975);
FORCEADD TAP..1
(4725 325);
FORCEPROP 3 LASTPIN (4675 325) SIG_NAME P5E_CPU0_PE2_TX_C_DP<0>
J 0
(4685 335);
DISPLAY 0.659574 (4685 335);
PAINT MONO (4685 335);
DISPLAY INVISIBLE (4685 335);
FORCEPROP 1 LASTPIN (4675 325) BN 0
J 0
(4663 333);
DISPLAY 0.680851 (4663 333);
PAINT GREEN (4663 333);
FORCEPROP 2 LAST CDS_LIB standard
J 0
(4725 325);
DISPLAY INVISIBLE (4725 325);
FORCEPROP 1 LAST BODY_TYPE PLUMBING
J 0
(4725 375);
DISPLAY 0.872340 (4725 375);
PAINT GREEN (4725 375);
DISPLAY INVISIBLE (4725 375);
FORCEPROP 1 LAST HDL_TAP TRUE
J 0
(5050 200);
DISPLAY 0.872340 (5050 200);
DISPLAY INVISIBLE (5050 200);
FORCEPROP 1 LAST PATH I173
J 0
(4723 325);
DISPLAY 0.872340 (4723 325);
PAINT GREEN (4723 325);
DISPLAY INVISIBLE (4723 325);
FORCEADD TAP..1
(4725 525);
FORCEPROP 3 LASTPIN (4675 525) SIG_NAME P5E_CPU0_PE2_TX_C_DP<1>
J 0
(4685 535);
DISPLAY 0.659574 (4685 535);
PAINT MONO (4685 535);
DISPLAY INVISIBLE (4685 535);
FORCEPROP 1 LASTPIN (4675 525) BN 1
J 0
(4663 533);
DISPLAY 0.680851 (4663 533);
PAINT GREEN (4663 533);
FORCEPROP 2 LAST CDS_LIB standard
J 0
(4725 525);
DISPLAY INVISIBLE (4725 525);
FORCEPROP 1 LAST BODY_TYPE PLUMBING
J 0
(4725 575);
DISPLAY 0.872340 (4725 575);
PAINT GREEN (4725 575);
DISPLAY INVISIBLE (4725 575);
FORCEPROP 1 LAST HDL_TAP TRUE
J 0
(5050 400);
DISPLAY 0.872340 (5050 400);
DISPLAY INVISIBLE (5050 400);
FORCEPROP 1 LAST PATH I174
J 0
(4723 525);
DISPLAY 0.872340 (4723 525);
PAINT GREEN (4723 525);
DISPLAY INVISIBLE (4723 525);
FORCEADD TAP..1
(4725 725);
FORCEPROP 3 LASTPIN (4675 725) SIG_NAME P5E_CPU0_PE2_TX_C_DP<2>
J 0
(4685 735);
DISPLAY 0.659574 (4685 735);
PAINT MONO (4685 735);
DISPLAY INVISIBLE (4685 735);
FORCEPROP 1 LASTPIN (4675 725) BN 2
J 0
(4663 733);
DISPLAY 0.680851 (4663 733);
PAINT GREEN (4663 733);
FORCEPROP 2 LAST CDS_LIB standard
J 0
(4725 725);
DISPLAY INVISIBLE (4725 725);
FORCEPROP 1 LAST BODY_TYPE PLUMBING
J 0
(4725 775);
DISPLAY 0.872340 (4725 775);
PAINT GREEN (4725 775);
DISPLAY INVISIBLE (4725 775);
FORCEPROP 1 LAST HDL_TAP TRUE
J 0
(5050 600);
DISPLAY 0.872340 (5050 600);
DISPLAY INVISIBLE (5050 600);
FORCEPROP 1 LAST PATH I175
J 0
(4723 725);
DISPLAY 0.872340 (4723 725);
PAINT GREEN (4723 725);
DISPLAY INVISIBLE (4723 725);
FORCEADD TAP..1
(4725 925);
FORCEPROP 3 LASTPIN (4675 925) SIG_NAME P5E_CPU0_PE2_TX_C_DP<3>
J 0
(4685 935);
DISPLAY 0.659574 (4685 935);
PAINT MONO (4685 935);
DISPLAY INVISIBLE (4685 935);
FORCEPROP 1 LASTPIN (4675 925) BN 3
J 0
(4663 933);
DISPLAY 0.680851 (4663 933);
PAINT GREEN (4663 933);
FORCEPROP 2 LAST CDS_LIB standard
J 0
(4725 925);
DISPLAY INVISIBLE (4725 925);
FORCEPROP 1 LAST BODY_TYPE PLUMBING
J 0
(4725 975);
DISPLAY 0.872340 (4725 975);
PAINT GREEN (4725 975);
DISPLAY INVISIBLE (4725 975);
FORCEPROP 1 LAST HDL_TAP TRUE
J 0
(5050 800);
DISPLAY 0.872340 (5050 800);
DISPLAY INVISIBLE (5050 800);
FORCEPROP 1 LAST PATH I176
J 0
(4723 925);
DISPLAY 0.872340 (4723 925);
PAINT GREEN (4723 925);
DISPLAY INVISIBLE (4723 925);
FORCEADD TAP..1
(4725 1125);
FORCEPROP 3 LASTPIN (4675 1125) SIG_NAME P5E_CPU0_PE2_TX_C_DP<4>
J 0
(4685 1135);
DISPLAY 0.659574 (4685 1135);
PAINT MONO (4685 1135);
DISPLAY INVISIBLE (4685 1135);
FORCEPROP 1 LASTPIN (4675 1125) BN 4
J 0
(4663 1133);
DISPLAY 0.680851 (4663 1133);
PAINT GREEN (4663 1133);
FORCEPROP 2 LAST CDS_LIB standard
J 0
(4725 1125);
DISPLAY INVISIBLE (4725 1125);
FORCEPROP 1 LAST BODY_TYPE PLUMBING
J 0
(4725 1175);
DISPLAY 0.872340 (4725 1175);
PAINT GREEN (4725 1175);
DISPLAY INVISIBLE (4725 1175);
FORCEPROP 1 LAST HDL_TAP TRUE
J 0
(5050 1000);
DISPLAY 0.872340 (5050 1000);
DISPLAY INVISIBLE (5050 1000);
FORCEPROP 1 LAST PATH I177
J 0
(4723 1125);
DISPLAY 0.872340 (4723 1125);
PAINT GREEN (4723 1125);
DISPLAY INVISIBLE (4723 1125);
FORCEADD TAP..1
(4525 1375);
FORCEPROP 3 LASTPIN (4475 1375) SIG_NAME P5E_CPU0_PE2_TX_C_DN<5>
J 0
(4485 1385);
DISPLAY 0.659574 (4485 1385);
PAINT MONO (4485 1385);
DISPLAY INVISIBLE (4485 1385);
FORCEPROP 1 LASTPIN (4475 1375) BN 5
J 0
(4463 1383);
DISPLAY 0.680851 (4463 1383);
PAINT GREEN (4463 1383);
FORCEPROP 2 LAST CDS_LIB standard
J 0
(4525 1375);
DISPLAY INVISIBLE (4525 1375);
FORCEPROP 1 LAST BODY_TYPE PLUMBING
J 0
(4525 1425);
DISPLAY 0.872340 (4525 1425);
PAINT GREEN (4525 1425);
DISPLAY INVISIBLE (4525 1425);
FORCEPROP 1 LAST HDL_TAP TRUE
J 0
(4850 1250);
DISPLAY 0.872340 (4850 1250);
DISPLAY INVISIBLE (4850 1250);
FORCEPROP 1 LAST PATH I178
J 0
(4523 1375);
DISPLAY 0.872340 (4523 1375);
PAINT GREEN (4523 1375);
DISPLAY INVISIBLE (4523 1375);
FORCEADD TAP..1
(4525 1175);
FORCEPROP 3 LASTPIN (4475 1175) SIG_NAME P5E_CPU0_PE2_TX_C_DN<4>
J 0
(4485 1185);
DISPLAY 0.659574 (4485 1185);
PAINT MONO (4485 1185);
DISPLAY INVISIBLE (4485 1185);
FORCEPROP 1 LASTPIN (4475 1175) BN 4
J 0
(4463 1183);
DISPLAY 0.680851 (4463 1183);
PAINT GREEN (4463 1183);
FORCEPROP 2 LAST CDS_LIB standard
J 0
(4525 1175);
DISPLAY INVISIBLE (4525 1175);
FORCEPROP 1 LAST BODY_TYPE PLUMBING
J 0
(4525 1225);
DISPLAY 0.872340 (4525 1225);
PAINT GREEN (4525 1225);
DISPLAY INVISIBLE (4525 1225);
FORCEPROP 1 LAST HDL_TAP TRUE
J 0
(4850 1050);
DISPLAY 0.872340 (4850 1050);
DISPLAY INVISIBLE (4850 1050);
FORCEPROP 1 LAST PATH I179
J 0
(4523 1175);
DISPLAY 0.872340 (4523 1175);
PAINT GREEN (4523 1175);
DISPLAY INVISIBLE (4523 1175);
FORCEADD TAP..1
R 2
(-1300 1575);
FORCEPROP 3 LASTPIN (-1250 1575) SIG_NAME P5E_CPU0_PE0_TX_DN<6>
J 0
(-1240 1585);
DISPLAY 0.659574 (-1240 1585);
PAINT MONO (-1240 1585);
DISPLAY INVISIBLE (-1240 1585);
FORCEPROP 1 LASTPIN (-1250 1575) BN 6
J 2
(-1238 1583);
DISPLAY 0.680851 (-1238 1583);
PAINT GREEN (-1238 1583);
FORCEPROP 2 LAST CDS_LIB standard
J 0
(-1300 1575);
DISPLAY INVISIBLE (-1300 1575);
FORCEPROP 1 LAST BODY_TYPE PLUMBING
J 2
(-1300 1625);
DISPLAY 0.872340 (-1300 1625);
PAINT GREEN (-1300 1625);
DISPLAY INVISIBLE (-1300 1625);
FORCEPROP 1 LAST HDL_TAP TRUE
J 2
(-1625 1450);
DISPLAY 0.872340 (-1625 1450);
DISPLAY INVISIBLE (-1625 1450);
FORCEPROP 1 LAST PATH I18
J 2
(-1298 1575);
DISPLAY 0.872340 (-1298 1575);
PAINT GREEN (-1298 1575);
DISPLAY INVISIBLE (-1298 1575);
FORCEADD TAP..1
(4525 1575);
FORCEPROP 3 LASTPIN (4475 1575) SIG_NAME P5E_CPU0_PE2_TX_C_DN<6>
J 0
(4485 1585);
DISPLAY 0.659574 (4485 1585);
PAINT MONO (4485 1585);
DISPLAY INVISIBLE (4485 1585);
FORCEPROP 1 LASTPIN (4475 1575) BN 6
J 0
(4463 1583);
DISPLAY 0.680851 (4463 1583);
PAINT GREEN (4463 1583);
FORCEPROP 2 LAST CDS_LIB standard
J 0
(4525 1575);
DISPLAY INVISIBLE (4525 1575);
FORCEPROP 1 LAST BODY_TYPE PLUMBING
J 0
(4525 1625);
DISPLAY 0.872340 (4525 1625);
PAINT GREEN (4525 1625);
DISPLAY INVISIBLE (4525 1625);
FORCEPROP 1 LAST HDL_TAP TRUE
J 0
(4850 1450);
DISPLAY 0.872340 (4850 1450);
DISPLAY INVISIBLE (4850 1450);
FORCEPROP 1 LAST PATH I180
J 0
(4523 1575);
DISPLAY 0.872340 (4523 1575);
PAINT GREEN (4523 1575);
DISPLAY INVISIBLE (4523 1575);
FORCEADD TAP..1
(4525 1775);
FORCEPROP 3 LASTPIN (4475 1775) SIG_NAME P5E_CPU0_PE2_TX_C_DN<7>
J 0
(4485 1785);
DISPLAY 0.659574 (4485 1785);
PAINT MONO (4485 1785);
DISPLAY INVISIBLE (4485 1785);
FORCEPROP 1 LASTPIN (4475 1775) BN 7
J 0
(4463 1783);
DISPLAY 0.680851 (4463 1783);
PAINT GREEN (4463 1783);
FORCEPROP 2 LAST CDS_LIB standard
J 0
(4525 1775);
DISPLAY INVISIBLE (4525 1775);
FORCEPROP 1 LAST BODY_TYPE PLUMBING
J 0
(4525 1825);
DISPLAY 0.872340 (4525 1825);
PAINT GREEN (4525 1825);
DISPLAY INVISIBLE (4525 1825);
FORCEPROP 1 LAST HDL_TAP TRUE
J 0
(4850 1650);
DISPLAY 0.872340 (4850 1650);
DISPLAY INVISIBLE (4850 1650);
FORCEPROP 1 LAST PATH I181
J 0
(4523 1775);
DISPLAY 0.872340 (4523 1775);
PAINT GREEN (4523 1775);
DISPLAY INVISIBLE (4523 1775);
FORCEADD TAP..1
(4725 1325);
FORCEPROP 3 LASTPIN (4675 1325) SIG_NAME P5E_CPU0_PE2_TX_C_DP<5>
J 0
(4685 1335);
DISPLAY 0.659574 (4685 1335);
PAINT MONO (4685 1335);
DISPLAY INVISIBLE (4685 1335);
FORCEPROP 1 LASTPIN (4675 1325) BN 5
J 0
(4663 1333);
DISPLAY 0.680851 (4663 1333);
PAINT GREEN (4663 1333);
FORCEPROP 2 LAST CDS_LIB standard
J 0
(4725 1325);
DISPLAY INVISIBLE (4725 1325);
FORCEPROP 1 LAST BODY_TYPE PLUMBING
J 0
(4725 1375);
DISPLAY 0.872340 (4725 1375);
PAINT GREEN (4725 1375);
DISPLAY INVISIBLE (4725 1375);
FORCEPROP 1 LAST HDL_TAP TRUE
J 0
(5050 1200);
DISPLAY 0.872340 (5050 1200);
DISPLAY INVISIBLE (5050 1200);
FORCEPROP 1 LAST PATH I182
J 0
(4723 1325);
DISPLAY 0.872340 (4723 1325);
PAINT GREEN (4723 1325);
DISPLAY INVISIBLE (4723 1325);
FORCEADD TAP..1
(4725 1525);
FORCEPROP 3 LASTPIN (4675 1525) SIG_NAME P5E_CPU0_PE2_TX_C_DP<6>
J 0
(4685 1535);
DISPLAY 0.659574 (4685 1535);
PAINT MONO (4685 1535);
DISPLAY INVISIBLE (4685 1535);
FORCEPROP 1 LASTPIN (4675 1525) BN 6
J 0
(4663 1533);
DISPLAY 0.680851 (4663 1533);
PAINT GREEN (4663 1533);
FORCEPROP 2 LAST CDS_LIB standard
J 0
(4725 1525);
DISPLAY INVISIBLE (4725 1525);
FORCEPROP 1 LAST BODY_TYPE PLUMBING
J 0
(4725 1575);
DISPLAY 0.872340 (4725 1575);
PAINT GREEN (4725 1575);
DISPLAY INVISIBLE (4725 1575);
FORCEPROP 1 LAST HDL_TAP TRUE
J 0
(5050 1400);
DISPLAY 0.872340 (5050 1400);
DISPLAY INVISIBLE (5050 1400);
FORCEPROP 1 LAST PATH I183
J 0
(4723 1525);
DISPLAY 0.872340 (4723 1525);
PAINT GREEN (4723 1525);
DISPLAY INVISIBLE (4723 1525);
FORCEADD TAP..1
(4725 1725);
FORCEPROP 3 LASTPIN (4675 1725) SIG_NAME P5E_CPU0_PE2_TX_C_DP<7>
J 0
(4685 1735);
DISPLAY 0.659574 (4685 1735);
PAINT MONO (4685 1735);
DISPLAY INVISIBLE (4685 1735);
FORCEPROP 1 LASTPIN (4675 1725) BN 7
J 0
(4663 1733);
DISPLAY 0.680851 (4663 1733);
PAINT GREEN (4663 1733);
FORCEPROP 2 LAST CDS_LIB standard
J 0
(4725 1725);
DISPLAY INVISIBLE (4725 1725);
FORCEPROP 1 LAST BODY_TYPE PLUMBING
J 0
(4725 1775);
DISPLAY 0.872340 (4725 1775);
PAINT GREEN (4725 1775);
DISPLAY INVISIBLE (4725 1775);
FORCEPROP 1 LAST HDL_TAP TRUE
J 0
(5050 1600);
DISPLAY 0.872340 (5050 1600);
DISPLAY INVISIBLE (5050 1600);
FORCEPROP 1 LAST PATH I184
J 0
(4723 1725);
DISPLAY 0.872340 (4723 1725);
PAINT GREEN (4723 1725);
DISPLAY INVISIBLE (4723 1725);
FORCEADD OFFPAGE..2
(5725 1800);
FORCEPROP 2 LAST $XR0 136 
J 0
(5914 1800);
DISPLAY 0.638298 (5914 1800);
PAINT MONO (5914 1800);
FORCEPROP 2 LAST CDS_LIB standard
J 0
(5725 1800);
DISPLAY INVISIBLE (5725 1800);
FORCEPROP 1 LAST OFFPAGE TRUE
J 0
(6050 1675);
DISPLAY 0.872340 (6050 1675);
DISPLAY INVISIBLE (6050 1675);
FORCEPROP 1 LAST COMMENT_BODY TRUE
J 0
(5680 1705);
DISPLAY 0.872340 (5680 1705);
PAINT GREEN (5680 1705);
DISPLAY INVISIBLE (5680 1705);
FORCEPROP 2 LAST PATH I185
J 0
(5925 1850);
DISPLAY 1.021277 (5925 1850);
DISPLAY INVISIBLE (5925 1850);
FORCEADD OFFPAGE..2
(5725 1750);
FORCEPROP 2 LAST $XR0 136 
J 0
(5914 1750);
DISPLAY 0.638298 (5914 1750);
PAINT MONO (5914 1750);
FORCEPROP 2 LAST CDS_LIB standard
J 0
(5725 1750);
DISPLAY INVISIBLE (5725 1750);
FORCEPROP 1 LAST OFFPAGE TRUE
J 0
(6050 1625);
DISPLAY 0.872340 (6050 1625);
DISPLAY INVISIBLE (6050 1625);
FORCEPROP 1 LAST COMMENT_BODY TRUE
J 0
(5680 1655);
DISPLAY 0.872340 (5680 1655);
PAINT GREEN (5680 1655);
DISPLAY INVISIBLE (5680 1655);
FORCEPROP 2 LAST PATH I186
J 0
(5925 1800);
DISPLAY 1.021277 (5925 1800);
DISPLAY INVISIBLE (5925 1800);
FORCEADD TAP..1
(4525 2350);
FORCEPROP 3 LASTPIN (4475 2350) SIG_NAME P5E_CPU0_PE2_TX_C_DN<8>
J 0
(4485 2360);
DISPLAY 0.659574 (4485 2360);
PAINT MONO (4485 2360);
DISPLAY INVISIBLE (4485 2360);
FORCEPROP 1 LASTPIN (4475 2350) BN 8
J 0
(4463 2358);
DISPLAY 0.680851 (4463 2358);
PAINT GREEN (4463 2358);
FORCEPROP 2 LAST CDS_LIB standard
J 0
(4525 2350);
DISPLAY INVISIBLE (4525 2350);
FORCEPROP 1 LAST BODY_TYPE PLUMBING
J 0
(4525 2400);
DISPLAY 0.872340 (4525 2400);
PAINT GREEN (4525 2400);
DISPLAY INVISIBLE (4525 2400);
FORCEPROP 1 LAST HDL_TAP TRUE
J 0
(4850 2225);
DISPLAY 0.872340 (4850 2225);
DISPLAY INVISIBLE (4850 2225);
FORCEPROP 1 LAST PATH I187
J 0
(4523 2350);
DISPLAY 0.872340 (4523 2350);
PAINT GREEN (4523 2350);
DISPLAY INVISIBLE (4523 2350);
FORCEADD TAP..1
(4525 2550);
FORCEPROP 3 LASTPIN (4475 2550) SIG_NAME P5E_CPU0_PE2_TX_C_DN<9>
J 0
(4485 2560);
DISPLAY 0.659574 (4485 2560);
PAINT MONO (4485 2560);
DISPLAY INVISIBLE (4485 2560);
FORCEPROP 1 LASTPIN (4475 2550) BN 9
J 0
(4463 2558);
DISPLAY 0.680851 (4463 2558);
PAINT GREEN (4463 2558);
FORCEPROP 2 LAST CDS_LIB standard
J 0
(4525 2550);
DISPLAY INVISIBLE (4525 2550);
FORCEPROP 1 LAST BODY_TYPE PLUMBING
J 0
(4525 2600);
DISPLAY 0.872340 (4525 2600);
PAINT GREEN (4525 2600);
DISPLAY INVISIBLE (4525 2600);
FORCEPROP 1 LAST HDL_TAP TRUE
J 0
(4850 2425);
DISPLAY 0.872340 (4850 2425);
DISPLAY INVISIBLE (4850 2425);
FORCEPROP 1 LAST PATH I188
J 0
(4523 2550);
DISPLAY 0.872340 (4523 2550);
PAINT GREEN (4523 2550);
DISPLAY INVISIBLE (4523 2550);
FORCEADD TAP..1
(4525 2750);
FORCEPROP 3 LASTPIN (4475 2750) SIG_NAME P5E_CPU0_PE2_TX_C_DN<10>
J 0
(4485 2760);
DISPLAY 0.659574 (4485 2760);
PAINT MONO (4485 2760);
DISPLAY INVISIBLE (4485 2760);
FORCEPROP 1 LASTPIN (4475 2750) BN 10
J 0
(4463 2758);
DISPLAY 0.680851 (4463 2758);
PAINT GREEN (4463 2758);
FORCEPROP 2 LAST CDS_LIB standard
J 0
(4525 2750);
DISPLAY INVISIBLE (4525 2750);
FORCEPROP 1 LAST BODY_TYPE PLUMBING
J 0
(4525 2800);
DISPLAY 0.872340 (4525 2800);
PAINT GREEN (4525 2800);
DISPLAY INVISIBLE (4525 2800);
FORCEPROP 1 LAST HDL_TAP TRUE
J 0
(4850 2625);
DISPLAY 0.872340 (4850 2625);
DISPLAY INVISIBLE (4850 2625);
FORCEPROP 1 LAST PATH I189
J 0
(4523 2750);
DISPLAY 0.872340 (4523 2750);
PAINT GREEN (4523 2750);
DISPLAY INVISIBLE (4523 2750);
FORCEADD TAP..1
R 2
(-1550 1725);
FORCEPROP 3 LASTPIN (-1500 1725) SIG_NAME P5E_CPU0_PE0_TX_DP<7>
J 0
(-1490 1735);
DISPLAY 0.659574 (-1490 1735);
PAINT MONO (-1490 1735);
DISPLAY INVISIBLE (-1490 1735);
FORCEPROP 1 LASTPIN (-1500 1725) BN 7
J 2
(-1488 1733);
DISPLAY 0.680851 (-1488 1733);
PAINT GREEN (-1488 1733);
FORCEPROP 2 LAST CDS_LIB standard
J 0
(-1550 1725);
DISPLAY INVISIBLE (-1550 1725);
FORCEPROP 1 LAST BODY_TYPE PLUMBING
J 2
(-1550 1775);
DISPLAY 0.872340 (-1550 1775);
PAINT GREEN (-1550 1775);
DISPLAY INVISIBLE (-1550 1775);
FORCEPROP 1 LAST HDL_TAP TRUE
J 2
(-1875 1600);
DISPLAY 0.872340 (-1875 1600);
DISPLAY INVISIBLE (-1875 1600);
FORCEPROP 1 LAST PATH I19
J 2
(-1548 1725);
DISPLAY 0.872340 (-1548 1725);
PAINT GREEN (-1548 1725);
DISPLAY INVISIBLE (-1548 1725);
FORCEADD TAP..1
(4525 2950);
FORCEPROP 3 LASTPIN (4475 2950) SIG_NAME P5E_CPU0_PE2_TX_C_DN<11>
J 0
(4485 2960);
DISPLAY 0.659574 (4485 2960);
PAINT MONO (4485 2960);
DISPLAY INVISIBLE (4485 2960);
FORCEPROP 1 LASTPIN (4475 2950) BN 11
J 0
(4463 2958);
DISPLAY 0.680851 (4463 2958);
PAINT GREEN (4463 2958);
FORCEPROP 2 LAST CDS_LIB standard
J 0
(4525 2950);
DISPLAY INVISIBLE (4525 2950);
FORCEPROP 1 LAST BODY_TYPE PLUMBING
J 0
(4525 3000);
DISPLAY 0.872340 (4525 3000);
PAINT GREEN (4525 3000);
DISPLAY INVISIBLE (4525 3000);
FORCEPROP 1 LAST HDL_TAP TRUE
J 0
(4850 2825);
DISPLAY 0.872340 (4850 2825);
DISPLAY INVISIBLE (4850 2825);
FORCEPROP 1 LAST PATH I190
J 0
(4523 2950);
DISPLAY 0.872340 (4523 2950);
PAINT GREEN (4523 2950);
DISPLAY INVISIBLE (4523 2950);
FORCEADD TAP..1
(4525 3150);
FORCEPROP 3 LASTPIN (4475 3150) SIG_NAME P5E_CPU0_PE2_TX_C_DN<12>
J 0
(4485 3160);
DISPLAY 0.659574 (4485 3160);
PAINT MONO (4485 3160);
DISPLAY INVISIBLE (4485 3160);
FORCEPROP 1 LASTPIN (4475 3150) BN 12
J 0
(4463 3158);
DISPLAY 0.680851 (4463 3158);
PAINT GREEN (4463 3158);
FORCEPROP 2 LAST CDS_LIB standard
J 0
(4525 3150);
DISPLAY INVISIBLE (4525 3150);
FORCEPROP 1 LAST BODY_TYPE PLUMBING
J 0
(4525 3200);
DISPLAY 0.872340 (4525 3200);
PAINT GREEN (4525 3200);
DISPLAY INVISIBLE (4525 3200);
FORCEPROP 1 LAST HDL_TAP TRUE
J 0
(4850 3025);
DISPLAY 0.872340 (4850 3025);
DISPLAY INVISIBLE (4850 3025);
FORCEPROP 1 LAST PATH I191
J 0
(4523 3150);
DISPLAY 0.872340 (4523 3150);
PAINT GREEN (4523 3150);
DISPLAY INVISIBLE (4523 3150);
FORCEADD TAP..1
(4725 2300);
FORCEPROP 3 LASTPIN (4675 2300) SIG_NAME P5E_CPU0_PE2_TX_C_DP<8>
J 0
(4685 2310);
DISPLAY 0.659574 (4685 2310);
PAINT MONO (4685 2310);
DISPLAY INVISIBLE (4685 2310);
FORCEPROP 1 LASTPIN (4675 2300) BN 8
J 0
(4663 2308);
DISPLAY 0.680851 (4663 2308);
PAINT GREEN (4663 2308);
FORCEPROP 2 LAST CDS_LIB standard
J 0
(4725 2300);
DISPLAY INVISIBLE (4725 2300);
FORCEPROP 1 LAST BODY_TYPE PLUMBING
J 0
(4725 2350);
DISPLAY 0.872340 (4725 2350);
PAINT GREEN (4725 2350);
DISPLAY INVISIBLE (4725 2350);
FORCEPROP 1 LAST HDL_TAP TRUE
J 0
(5050 2175);
DISPLAY 0.872340 (5050 2175);
DISPLAY INVISIBLE (5050 2175);
FORCEPROP 1 LAST PATH I192
J 0
(4723 2300);
DISPLAY 0.872340 (4723 2300);
PAINT GREEN (4723 2300);
DISPLAY INVISIBLE (4723 2300);
FORCEADD TAP..1
(4725 2500);
FORCEPROP 3 LASTPIN (4675 2500) SIG_NAME P5E_CPU0_PE2_TX_C_DP<9>
J 0
(4685 2510);
DISPLAY 0.659574 (4685 2510);
PAINT MONO (4685 2510);
DISPLAY INVISIBLE (4685 2510);
FORCEPROP 1 LASTPIN (4675 2500) BN 9
J 0
(4663 2508);
DISPLAY 0.680851 (4663 2508);
PAINT GREEN (4663 2508);
FORCEPROP 2 LAST CDS_LIB standard
J 0
(4725 2500);
DISPLAY INVISIBLE (4725 2500);
FORCEPROP 1 LAST BODY_TYPE PLUMBING
J 0
(4725 2550);
DISPLAY 0.872340 (4725 2550);
PAINT GREEN (4725 2550);
DISPLAY INVISIBLE (4725 2550);
FORCEPROP 1 LAST HDL_TAP TRUE
J 0
(5050 2375);
DISPLAY 0.872340 (5050 2375);
DISPLAY INVISIBLE (5050 2375);
FORCEPROP 1 LAST PATH I193
J 0
(4723 2500);
DISPLAY 0.872340 (4723 2500);
PAINT GREEN (4723 2500);
DISPLAY INVISIBLE (4723 2500);
FORCEADD TAP..1
(4725 2700);
FORCEPROP 3 LASTPIN (4675 2700) SIG_NAME P5E_CPU0_PE2_TX_C_DP<10>
J 0
(4685 2710);
DISPLAY 0.659574 (4685 2710);
PAINT MONO (4685 2710);
DISPLAY INVISIBLE (4685 2710);
FORCEPROP 1 LASTPIN (4675 2700) BN 10
J 0
(4663 2708);
DISPLAY 0.680851 (4663 2708);
PAINT GREEN (4663 2708);
FORCEPROP 2 LAST CDS_LIB standard
J 0
(4725 2700);
DISPLAY INVISIBLE (4725 2700);
FORCEPROP 1 LAST BODY_TYPE PLUMBING
J 0
(4725 2750);
DISPLAY 0.872340 (4725 2750);
PAINT GREEN (4725 2750);
DISPLAY INVISIBLE (4725 2750);
FORCEPROP 1 LAST HDL_TAP TRUE
J 0
(5050 2575);
DISPLAY 0.872340 (5050 2575);
DISPLAY INVISIBLE (5050 2575);
FORCEPROP 1 LAST PATH I194
J 0
(4723 2700);
DISPLAY 0.872340 (4723 2700);
PAINT GREEN (4723 2700);
DISPLAY INVISIBLE (4723 2700);
FORCEADD TAP..1
(4725 2900);
FORCEPROP 3 LASTPIN (4675 2900) SIG_NAME P5E_CPU0_PE2_TX_C_DP<11>
J 0
(4685 2910);
DISPLAY 0.659574 (4685 2910);
PAINT MONO (4685 2910);
DISPLAY INVISIBLE (4685 2910);
FORCEPROP 1 LASTPIN (4675 2900) BN 11
J 0
(4663 2908);
DISPLAY 0.680851 (4663 2908);
PAINT GREEN (4663 2908);
FORCEPROP 2 LAST CDS_LIB standard
J 0
(4725 2900);
DISPLAY INVISIBLE (4725 2900);
FORCEPROP 1 LAST BODY_TYPE PLUMBING
J 0
(4725 2950);
DISPLAY 0.872340 (4725 2950);
PAINT GREEN (4725 2950);
DISPLAY INVISIBLE (4725 2950);
FORCEPROP 1 LAST HDL_TAP TRUE
J 0
(5050 2775);
DISPLAY 0.872340 (5050 2775);
DISPLAY INVISIBLE (5050 2775);
FORCEPROP 1 LAST PATH I195
J 0
(4723 2900);
DISPLAY 0.872340 (4723 2900);
PAINT GREEN (4723 2900);
DISPLAY INVISIBLE (4723 2900);
FORCEADD TAP..1
(4725 3100);
FORCEPROP 3 LASTPIN (4675 3100) SIG_NAME P5E_CPU0_PE2_TX_C_DP<12>
J 0
(4685 3110);
DISPLAY 0.659574 (4685 3110);
PAINT MONO (4685 3110);
DISPLAY INVISIBLE (4685 3110);
FORCEPROP 1 LASTPIN (4675 3100) BN 12
J 0
(4663 3108);
DISPLAY 0.680851 (4663 3108);
PAINT GREEN (4663 3108);
FORCEPROP 2 LAST CDS_LIB standard
J 0
(4725 3100);
DISPLAY INVISIBLE (4725 3100);
FORCEPROP 1 LAST BODY_TYPE PLUMBING
J 0
(4725 3150);
DISPLAY 0.872340 (4725 3150);
PAINT GREEN (4725 3150);
DISPLAY INVISIBLE (4725 3150);
FORCEPROP 1 LAST HDL_TAP TRUE
J 0
(5050 2975);
DISPLAY 0.872340 (5050 2975);
DISPLAY INVISIBLE (5050 2975);
FORCEPROP 1 LAST PATH I196
J 0
(4723 3100);
DISPLAY 0.872340 (4723 3100);
PAINT GREEN (4723 3100);
DISPLAY INVISIBLE (4723 3100);
FORCEADD TAP..1
(4525 3350);
FORCEPROP 3 LASTPIN (4475 3350) SIG_NAME P5E_CPU0_PE2_TX_C_DN<13>
J 0
(4485 3360);
DISPLAY 0.659574 (4485 3360);
PAINT MONO (4485 3360);
DISPLAY INVISIBLE (4485 3360);
FORCEPROP 1 LASTPIN (4475 3350) BN 13
J 0
(4463 3358);
DISPLAY 0.680851 (4463 3358);
PAINT GREEN (4463 3358);
FORCEPROP 2 LAST CDS_LIB standard
J 0
(4525 3350);
DISPLAY INVISIBLE (4525 3350);
FORCEPROP 1 LAST BODY_TYPE PLUMBING
J 0
(4525 3400);
DISPLAY 0.872340 (4525 3400);
PAINT GREEN (4525 3400);
DISPLAY INVISIBLE (4525 3400);
FORCEPROP 1 LAST HDL_TAP TRUE
J 0
(4850 3225);
DISPLAY 0.872340 (4850 3225);
DISPLAY INVISIBLE (4850 3225);
FORCEPROP 1 LAST PATH I197
J 0
(4523 3350);
DISPLAY 0.872340 (4523 3350);
PAINT GREEN (4523 3350);
DISPLAY INVISIBLE (4523 3350);
FORCEADD TAP..1
(4525 3550);
FORCEPROP 3 LASTPIN (4475 3550) SIG_NAME P5E_CPU0_PE2_TX_C_DN<14>
J 0
(4485 3560);
DISPLAY 0.659574 (4485 3560);
PAINT MONO (4485 3560);
DISPLAY INVISIBLE (4485 3560);
FORCEPROP 1 LASTPIN (4475 3550) BN 14
J 0
(4463 3558);
DISPLAY 0.680851 (4463 3558);
PAINT GREEN (4463 3558);
FORCEPROP 2 LAST CDS_LIB standard
J 0
(4525 3550);
DISPLAY INVISIBLE (4525 3550);
FORCEPROP 1 LAST BODY_TYPE PLUMBING
J 0
(4525 3600);
DISPLAY 0.872340 (4525 3600);
PAINT GREEN (4525 3600);
DISPLAY INVISIBLE (4525 3600);
FORCEPROP 1 LAST HDL_TAP TRUE
J 0
(4850 3425);
DISPLAY 0.872340 (4850 3425);
DISPLAY INVISIBLE (4850 3425);
FORCEPROP 1 LAST PATH I198
J 0
(4523 3550);
DISPLAY 0.872340 (4523 3550);
PAINT GREEN (4523 3550);
DISPLAY INVISIBLE (4523 3550);
FORCEADD TAP..1
(4525 3750);
FORCEPROP 3 LASTPIN (4475 3750) SIG_NAME P5E_CPU0_PE2_TX_C_DN<15>
J 0
(4485 3760);
DISPLAY 0.659574 (4485 3760);
PAINT MONO (4485 3760);
DISPLAY INVISIBLE (4485 3760);
FORCEPROP 1 LASTPIN (4475 3750) BN 15
J 0
(4463 3758);
DISPLAY 0.680851 (4463 3758);
PAINT GREEN (4463 3758);
FORCEPROP 2 LAST CDS_LIB standard
J 0
(4525 3750);
DISPLAY INVISIBLE (4525 3750);
FORCEPROP 1 LAST BODY_TYPE PLUMBING
J 0
(4525 3800);
DISPLAY 0.872340 (4525 3800);
PAINT GREEN (4525 3800);
DISPLAY INVISIBLE (4525 3800);
FORCEPROP 1 LAST HDL_TAP TRUE
J 0
(4850 3625);
DISPLAY 0.872340 (4850 3625);
DISPLAY INVISIBLE (4850 3625);
FORCEPROP 1 LAST PATH I199
J 0
(4523 3750);
DISPLAY 0.872340 (4523 3750);
PAINT GREEN (4523 3750);
DISPLAY INVISIBLE (4523 3750);
FORCEADD OFFPAGE..1
(-2500 1750);
FORCEPROP 2 LAST $XR0 29 
J 0
(-2751 1750);
DISPLAY 0.638298 (-2751 1750);
PAINT MONO (-2751 1750);
FORCEPROP 2 LAST CDS_LIB standard
J 0
(-2500 1750);
DISPLAY INVISIBLE (-2500 1750);
FORCEPROP 1 LAST OFFPAGE TRUE
J 0
(-2175 1625);
DISPLAY 0.872340 (-2175 1625);
DISPLAY INVISIBLE (-2175 1625);
FORCEPROP 1 LAST COMMENT_BODY TRUE
J 0
(-2375 1650);
DISPLAY 0.872340 (-2375 1650);
PAINT GREEN (-2375 1650);
DISPLAY INVISIBLE (-2375 1650);
FORCEPROP 2 LAST PATH I2
J 0
(-2775 1800);
DISPLAY 1.021277 (-2775 1800);
DISPLAY INVISIBLE (-2775 1800);
FORCEADD TAP..1
R 2
(-1300 1775);
FORCEPROP 3 LASTPIN (-1250 1775) SIG_NAME P5E_CPU0_PE0_TX_DN<7>
J 0
(-1240 1785);
DISPLAY 0.659574 (-1240 1785);
PAINT MONO (-1240 1785);
DISPLAY INVISIBLE (-1240 1785);
FORCEPROP 1 LASTPIN (-1250 1775) BN 7
J 2
(-1238 1783);
DISPLAY 0.680851 (-1238 1783);
PAINT GREEN (-1238 1783);
FORCEPROP 2 LAST CDS_LIB standard
J 0
(-1300 1775);
DISPLAY INVISIBLE (-1300 1775);
FORCEPROP 1 LAST BODY_TYPE PLUMBING
J 2
(-1300 1825);
DISPLAY 0.872340 (-1300 1825);
PAINT GREEN (-1300 1825);
DISPLAY INVISIBLE (-1300 1825);
FORCEPROP 1 LAST HDL_TAP TRUE
J 2
(-1625 1650);
DISPLAY 0.872340 (-1625 1650);
DISPLAY INVISIBLE (-1625 1650);
FORCEPROP 1 LAST PATH I20
J 2
(-1298 1775);
DISPLAY 0.872340 (-1298 1775);
PAINT GREEN (-1298 1775);
DISPLAY INVISIBLE (-1298 1775);
FORCEADD TAP..1
(4725 3300);
FORCEPROP 3 LASTPIN (4675 3300) SIG_NAME P5E_CPU0_PE2_TX_C_DP<13>
J 0
(4685 3310);
DISPLAY 0.659574 (4685 3310);
PAINT MONO (4685 3310);
DISPLAY INVISIBLE (4685 3310);
FORCEPROP 1 LASTPIN (4675 3300) BN 13
J 0
(4663 3308);
DISPLAY 0.680851 (4663 3308);
PAINT GREEN (4663 3308);
FORCEPROP 2 LAST CDS_LIB standard
J 0
(4725 3300);
DISPLAY INVISIBLE (4725 3300);
FORCEPROP 1 LAST BODY_TYPE PLUMBING
J 0
(4725 3350);
DISPLAY 0.872340 (4725 3350);
PAINT GREEN (4725 3350);
DISPLAY INVISIBLE (4725 3350);
FORCEPROP 1 LAST HDL_TAP TRUE
J 0
(5050 3175);
DISPLAY 0.872340 (5050 3175);
DISPLAY INVISIBLE (5050 3175);
FORCEPROP 1 LAST PATH I200
J 0
(4723 3300);
DISPLAY 0.872340 (4723 3300);
PAINT GREEN (4723 3300);
DISPLAY INVISIBLE (4723 3300);
FORCEADD TAP..1
(4725 3500);
FORCEPROP 3 LASTPIN (4675 3500) SIG_NAME P5E_CPU0_PE2_TX_C_DP<14>
J 0
(4685 3510);
DISPLAY 0.659574 (4685 3510);
PAINT MONO (4685 3510);
DISPLAY INVISIBLE (4685 3510);
FORCEPROP 1 LASTPIN (4675 3500) BN 14
J 0
(4663 3508);
DISPLAY 0.680851 (4663 3508);
PAINT GREEN (4663 3508);
FORCEPROP 2 LAST CDS_LIB standard
J 0
(4725 3500);
DISPLAY INVISIBLE (4725 3500);
FORCEPROP 1 LAST BODY_TYPE PLUMBING
J 0
(4725 3550);
DISPLAY 0.872340 (4725 3550);
PAINT GREEN (4725 3550);
DISPLAY INVISIBLE (4725 3550);
FORCEPROP 1 LAST HDL_TAP TRUE
J 0
(5050 3375);
DISPLAY 0.872340 (5050 3375);
DISPLAY INVISIBLE (5050 3375);
FORCEPROP 1 LAST PATH I201
J 0
(4723 3500);
DISPLAY 0.872340 (4723 3500);
PAINT GREEN (4723 3500);
DISPLAY INVISIBLE (4723 3500);
FORCEADD TAP..1
(4725 3700);
FORCEPROP 3 LASTPIN (4675 3700) SIG_NAME P5E_CPU0_PE2_TX_C_DP<15>
J 0
(4685 3710);
DISPLAY 0.659574 (4685 3710);
PAINT MONO (4685 3710);
DISPLAY INVISIBLE (4685 3710);
FORCEPROP 1 LASTPIN (4675 3700) BN 15
J 0
(4663 3708);
DISPLAY 0.680851 (4663 3708);
PAINT GREEN (4663 3708);
FORCEPROP 2 LAST CDS_LIB standard
J 0
(4725 3700);
DISPLAY INVISIBLE (4725 3700);
FORCEPROP 1 LAST BODY_TYPE PLUMBING
J 0
(4725 3750);
DISPLAY 0.872340 (4725 3750);
PAINT GREEN (4725 3750);
DISPLAY INVISIBLE (4725 3750);
FORCEPROP 1 LAST HDL_TAP TRUE
J 0
(5050 3575);
DISPLAY 0.872340 (5050 3575);
DISPLAY INVISIBLE (5050 3575);
FORCEPROP 1 LAST PATH I202
J 0
(4723 3700);
DISPLAY 0.872340 (4723 3700);
PAINT GREEN (4723 3700);
DISPLAY INVISIBLE (4723 3700);
FORCEADD OFFPAGE..2
(5725 3725);
FORCEPROP 2 LAST $XR0 137 
J 0
(5914 3725);
DISPLAY 0.638298 (5914 3725);
PAINT MONO (5914 3725);
FORCEPROP 2 LAST CDS_LIB standard
J 0
(5725 3725);
DISPLAY INVISIBLE (5725 3725);
FORCEPROP 1 LAST OFFPAGE TRUE
J 0
(6050 3600);
DISPLAY 0.872340 (6050 3600);
DISPLAY INVISIBLE (6050 3600);
FORCEPROP 1 LAST COMMENT_BODY TRUE
J 0
(5680 3630);
DISPLAY 0.872340 (5680 3630);
PAINT GREEN (5680 3630);
DISPLAY INVISIBLE (5680 3630);
FORCEPROP 2 LAST PATH I203
J 0
(5925 3775);
DISPLAY 1.021277 (5925 3775);
DISPLAY INVISIBLE (5925 3775);
FORCEADD OFFPAGE..2
(5725 3775);
FORCEPROP 2 LAST $XR0 137 
J 0
(5914 3775);
DISPLAY 0.638298 (5914 3775);
PAINT MONO (5914 3775);
FORCEPROP 2 LAST CDS_LIB standard
J 0
(5725 3775);
DISPLAY INVISIBLE (5725 3775);
FORCEPROP 1 LAST OFFPAGE TRUE
J 0
(6050 3650);
DISPLAY 0.872340 (6050 3650);
DISPLAY INVISIBLE (6050 3650);
FORCEPROP 1 LAST COMMENT_BODY TRUE
J 0
(5680 3680);
DISPLAY 0.872340 (5680 3680);
PAINT GREEN (5680 3680);
DISPLAY INVISIBLE (5680 3680);
FORCEPROP 2 LAST PATH I204
J 0
(5925 3825);
DISPLAY 1.021277 (5925 3825);
DISPLAY INVISIBLE (5925 3825);
FORCEADD TAP..1
(4525 375);
FORCEPROP 3 LASTPIN (4475 375) SIG_NAME P5E_CPU0_PE2_TX_C_DN<0>
J 0
(4485 385);
DISPLAY 0.659574 (4485 385);
PAINT MONO (4485 385);
DISPLAY INVISIBLE (4485 385);
FORCEPROP 1 LASTPIN (4475 375) BN 0
J 0
(4463 383);
DISPLAY 0.680851 (4463 383);
PAINT GREEN (4463 383);
FORCEPROP 2 LAST CDS_LIB standard
J 0
(4525 375);
DISPLAY INVISIBLE (4525 375);
FORCEPROP 1 LAST BODY_TYPE PLUMBING
J 0
(4525 425);
DISPLAY 0.872340 (4525 425);
PAINT GREEN (4525 425);
DISPLAY INVISIBLE (4525 425);
FORCEPROP 1 LAST HDL_TAP TRUE
J 0
(4850 250);
DISPLAY 0.872340 (4850 250);
DISPLAY INVISIBLE (4850 250);
FORCEPROP 1 LAST PATH I205
J 0
(4523 375);
DISPLAY 0.872340 (4523 375);
PAINT GREEN (4523 375);
DISPLAY INVISIBLE (4523 375);
FORCEADD Q_CAP_DIFFBUS..2
R 2
(3975 1125);
FORCEPROP 1 LAST PART_NUMBER SP_CH4221MEE01
J 2
(3859 1213);
DISPLAY 0.574468 (3859 1213);
PAINT GREEN (3859 1213);
DISPLAY INVISIBLE (3859 1213);
FORCEPROP 2 LAST VALUE DIFF BUS_0.22UF
J 2
(3825 1125);
DISPLAY 0.553191 (3825 1125);
FORCEPROP 1 LAST $LOCATION C957
J 2
(4209 1142);
DISPLAY 0.723404 (4209 1142);
PAINT GREEN (4209 1142);
FORCEPROP 2 LASTPIN (4050 1125) $PN 1
J 0
(4060 1135);
DISPLAY 0.808511 (4060 1135);
FORCEPROP 2 LASTPIN (3900 1125) $PN 2
J 2
(3890 1135);
DISPLAY 0.808511 (3890 1135);
FORCEPROP 2 LAST TOLERANCE 20%
J 2
(3900 1175);
DISPLAY 0.553191 (3900 1175);
DISPLAY INVISIBLE (3900 1175);
FORCEPROP 2 LAST PACK_TYPE C0201
J 2
(3800 1175);
DISPLAY 0.553191 (3800 1175);
DISPLAY INVISIBLE (3800 1175);
FORCEPROP 1 LAST MATERIAL X6S
J 2
(3984 1204);
DISPLAY 0.574468 (3984 1204);
PAINT GREEN (3984 1204);
DISPLAY INVISIBLE (3984 1204);
FORCEPROP 2 LAST VOLTAGE 6.3V
J 2
(3625 1175);
DISPLAY 0.553191 (3625 1175);
DISPLAY INVISIBLE (3625 1175);
FORCEPROP 1 LAST CDS_LMAN_SYM_OUTLINE -25,50,25,-50
J 2
(3975 1125);
DISPLAY 0.468085 (3975 1125);
PAINT GREEN (3975 1125);
DISPLAY INVISIBLE (3975 1125);
FORCEPROP 2 LAST CDS_LIB pure_quanta
J 2
(3975 1125);
DISPLAY INVISIBLE (3975 1125);
FORCEPROP 1 LAST PIN_NAMES_ROTATE TRUE
J 2
(3975 1125);
DISPLAY 0.489362 (3975 1125);
PAINT GREEN (3975 1125);
DISPLAY INVISIBLE (3975 1125);
FORCEPROP 1 LAST PATH I206
J 2
(3975 1125);
DISPLAY 0.723404 (3975 1125);
DISPLAY INVISIBLE (3975 1125);
FORCEPROP 1 LAST $LOCATION C957
J 0
(4225 1200);
DISPLAY 1.021277 (4225 1200);
DISPLAY INVISIBLE (4225 1200);
FORCEPROP 2 LAST CDS_LOCATION C957
J 0
(4225 1200);
DISPLAY 1.021277 (4225 1200);
DISPLAY INVISIBLE (4225 1200);
FORCEPROP 2 LAST $SEC 1
J 2
(4150 1200);
DISPLAY 0.680851 (4150 1200);
PAINT MONO (4150 1200);
DISPLAY INVISIBLE (4150 1200);
FORCEPROP 2 LAST CDS_SEC 1
J 2
(4150 1200);
DISPLAY 0.680851 (4150 1200);
DISPLAY INVISIBLE (4150 1200);
FORCEADD Q_CAP_DIFFBUS..2
R 2
(3975 1175);
FORCEPROP 1 LAST PART_NUMBER SP_CH4221MEE01
J 2
(3859 1263);
DISPLAY 0.574468 (3859 1263);
PAINT GREEN (3859 1263);
DISPLAY INVISIBLE (3859 1263);
FORCEPROP 2 LAST VALUE DIFF BUS_0.22UF
J 2
(3825 1175);
DISPLAY 0.553191 (3825 1175);
FORCEPROP 1 LAST $LOCATION C956
J 2
(4209 1192);
DISPLAY 0.723404 (4209 1192);
PAINT GREEN (4209 1192);
FORCEPROP 2 LASTPIN (4050 1175) $PN 1
J 0
(4060 1185);
DISPLAY 0.808511 (4060 1185);
FORCEPROP 2 LASTPIN (3900 1175) $PN 2
J 2
(3890 1185);
DISPLAY 0.808511 (3890 1185);
FORCEPROP 2 LAST TOLERANCE 20%
J 2
(3900 1225);
DISPLAY 0.553191 (3900 1225);
DISPLAY INVISIBLE (3900 1225);
FORCEPROP 2 LAST PACK_TYPE C0201
J 2
(3800 1225);
DISPLAY 0.553191 (3800 1225);
DISPLAY INVISIBLE (3800 1225);
FORCEPROP 1 LAST MATERIAL X6S
J 2
(3984 1254);
DISPLAY 0.574468 (3984 1254);
PAINT GREEN (3984 1254);
DISPLAY INVISIBLE (3984 1254);
FORCEPROP 2 LAST VOLTAGE 6.3V
J 2
(3625 1225);
DISPLAY 0.553191 (3625 1225);
DISPLAY INVISIBLE (3625 1225);
FORCEPROP 1 LAST CDS_LMAN_SYM_OUTLINE -25,50,25,-50
J 2
(3975 1175);
DISPLAY 0.468085 (3975 1175);
PAINT GREEN (3975 1175);
DISPLAY INVISIBLE (3975 1175);
FORCEPROP 2 LAST CDS_LIB pure_quanta
J 2
(3975 1175);
DISPLAY INVISIBLE (3975 1175);
FORCEPROP 1 LAST PIN_NAMES_ROTATE TRUE
J 2
(3975 1175);
DISPLAY 0.489362 (3975 1175);
PAINT GREEN (3975 1175);
DISPLAY INVISIBLE (3975 1175);
FORCEPROP 1 LAST PATH I207
J 2
(3975 1175);
DISPLAY 0.723404 (3975 1175);
DISPLAY INVISIBLE (3975 1175);
FORCEPROP 1 LAST $LOCATION C956
J 0
(4225 1250);
DISPLAY 1.021277 (4225 1250);
DISPLAY INVISIBLE (4225 1250);
FORCEPROP 2 LAST CDS_LOCATION C956
J 0
(4225 1250);
DISPLAY 1.021277 (4225 1250);
DISPLAY INVISIBLE (4225 1250);
FORCEPROP 2 LAST $SEC 1
J 2
(4150 1250);
DISPLAY 0.680851 (4150 1250);
PAINT MONO (4150 1250);
DISPLAY INVISIBLE (4150 1250);
FORCEPROP 2 LAST CDS_SEC 1
J 2
(4150 1250);
DISPLAY 0.680851 (4150 1250);
DISPLAY INVISIBLE (4150 1250);
FORCEADD Q_CAP_DIFFBUS..2
R 2
(3975 1325);
FORCEPROP 1 LAST PART_NUMBER SP_CH4221MEE01
J 2
(3859 1413);
DISPLAY 0.574468 (3859 1413);
PAINT GREEN (3859 1413);
DISPLAY INVISIBLE (3859 1413);
FORCEPROP 2 LAST VALUE DIFF BUS_0.22UF
J 2
(3825 1325);
DISPLAY 0.553191 (3825 1325);
FORCEPROP 1 LAST $LOCATION C955
J 2
(4209 1342);
DISPLAY 0.723404 (4209 1342);
PAINT GREEN (4209 1342);
FORCEPROP 2 LASTPIN (4050 1325) $PN 1
J 0
(4060 1335);
DISPLAY 0.808511 (4060 1335);
FORCEPROP 2 LASTPIN (3900 1325) $PN 2
J 2
(3890 1335);
DISPLAY 0.808511 (3890 1335);
FORCEPROP 2 LAST TOLERANCE 20%
J 2
(3900 1375);
DISPLAY 0.553191 (3900 1375);
DISPLAY INVISIBLE (3900 1375);
FORCEPROP 2 LAST PACK_TYPE C0201
J 2
(3800 1375);
DISPLAY 0.553191 (3800 1375);
DISPLAY INVISIBLE (3800 1375);
FORCEPROP 1 LAST MATERIAL X6S
J 2
(3984 1404);
DISPLAY 0.574468 (3984 1404);
PAINT GREEN (3984 1404);
DISPLAY INVISIBLE (3984 1404);
FORCEPROP 2 LAST VOLTAGE 6.3V
J 2
(3625 1375);
DISPLAY 0.553191 (3625 1375);
DISPLAY INVISIBLE (3625 1375);
FORCEPROP 1 LAST CDS_LMAN_SYM_OUTLINE -25,50,25,-50
J 2
(3975 1325);
DISPLAY 0.468085 (3975 1325);
PAINT GREEN (3975 1325);
DISPLAY INVISIBLE (3975 1325);
FORCEPROP 2 LAST CDS_LIB pure_quanta
J 2
(3975 1325);
DISPLAY INVISIBLE (3975 1325);
FORCEPROP 1 LAST PIN_NAMES_ROTATE TRUE
J 2
(3975 1325);
DISPLAY 0.489362 (3975 1325);
PAINT GREEN (3975 1325);
DISPLAY INVISIBLE (3975 1325);
FORCEPROP 1 LAST PATH I208
J 2
(3975 1325);
DISPLAY 0.723404 (3975 1325);
DISPLAY INVISIBLE (3975 1325);
FORCEPROP 1 LAST $LOCATION C955
J 0
(4225 1400);
DISPLAY 1.021277 (4225 1400);
DISPLAY INVISIBLE (4225 1400);
FORCEPROP 2 LAST CDS_LOCATION C955
J 0
(4225 1400);
DISPLAY 1.021277 (4225 1400);
DISPLAY INVISIBLE (4225 1400);
FORCEPROP 2 LAST $SEC 1
J 2
(4150 1400);
DISPLAY 0.680851 (4150 1400);
PAINT MONO (4150 1400);
DISPLAY INVISIBLE (4150 1400);
FORCEPROP 2 LAST CDS_SEC 1
J 2
(4150 1400);
DISPLAY 0.680851 (4150 1400);
DISPLAY INVISIBLE (4150 1400);
FORCEADD Q_CAP_DIFFBUS..2
R 2
(-575 375);
FORCEPROP 1 LAST PART_NUMBER SP_CH4221MEE01
J 2
(-691 463);
DISPLAY 0.574468 (-691 463);
PAINT GREEN (-691 463);
DISPLAY INVISIBLE (-691 463);
FORCEPROP 2 LAST VALUE DIFF BUS_0.22UF
J 2
(-725 375);
DISPLAY 0.553191 (-725 375);
FORCEPROP 1 LAST $LOCATION C932
J 2
(-341 392);
DISPLAY 0.723404 (-341 392);
PAINT GREEN (-341 392);
FORCEPROP 2 LASTPIN (-500 375) $PN 1
J 0
(-490 385);
DISPLAY 0.808511 (-490 385);
FORCEPROP 2 LASTPIN (-650 375) $PN 2
J 2
(-660 385);
DISPLAY 0.808511 (-660 385);
FORCEPROP 2 LAST TOLERANCE 20%
J 2
(-650 425);
DISPLAY 0.553191 (-650 425);
DISPLAY INVISIBLE (-650 425);
FORCEPROP 2 LAST PACK_TYPE C0201
J 2
(-750 425);
DISPLAY 0.553191 (-750 425);
DISPLAY INVISIBLE (-750 425);
FORCEPROP 1 LAST MATERIAL X6S
J 2
(-566 454);
DISPLAY 0.574468 (-566 454);
PAINT GREEN (-566 454);
DISPLAY INVISIBLE (-566 454);
FORCEPROP 2 LAST VOLTAGE 6.3V
J 2
(-925 425);
DISPLAY 0.553191 (-925 425);
DISPLAY INVISIBLE (-925 425);
FORCEPROP 1 LAST CDS_LMAN_SYM_OUTLINE -25,50,25,-50
J 2
(-575 375);
DISPLAY 0.468085 (-575 375);
PAINT GREEN (-575 375);
DISPLAY INVISIBLE (-575 375);
FORCEPROP 2 LAST CDS_LIB pure_quanta
J 2
(-575 375);
DISPLAY INVISIBLE (-575 375);
FORCEPROP 1 LAST PIN_NAMES_ROTATE TRUE
J 2
(-575 375);
DISPLAY 0.489362 (-575 375);
PAINT GREEN (-575 375);
DISPLAY INVISIBLE (-575 375);
FORCEPROP 1 LAST PATH I21
J 2
(-575 375);
DISPLAY 0.723404 (-575 375);
DISPLAY INVISIBLE (-575 375);
FORCEPROP 1 LAST $LOCATION C932
J 0
(-325 450);
DISPLAY 1.021277 (-325 450);
DISPLAY INVISIBLE (-325 450);
FORCEPROP 2 LAST CDS_LOCATION C932
J 0
(-325 450);
DISPLAY 1.021277 (-325 450);
DISPLAY INVISIBLE (-325 450);
FORCEPROP 2 LAST $SEC 1
J 2
(-400 450);
DISPLAY 0.680851 (-400 450);
PAINT MONO (-400 450);
DISPLAY INVISIBLE (-400 450);
FORCEPROP 2 LAST CDS_SEC 1
J 2
(-400 450);
DISPLAY 0.680851 (-400 450);
DISPLAY INVISIBLE (-400 450);
FORCEADD Q_CAP_DIFFBUS..2
R 2
(-575 325);
FORCEPROP 1 LAST PART_NUMBER SP_CH4221MEE01
J 2
(-691 413);
DISPLAY 0.574468 (-691 413);
PAINT GREEN (-691 413);
DISPLAY INVISIBLE (-691 413);
FORCEPROP 2 LAST VALUE DIFF BUS_0.22UF
J 2
(-725 325);
DISPLAY 0.553191 (-725 325);
FORCEPROP 1 LAST $LOCATION C933
J 2
(-341 342);
DISPLAY 0.723404 (-341 342);
PAINT GREEN (-341 342);
FORCEPROP 2 LASTPIN (-500 325) $PN 1
J 0
(-490 335);
DISPLAY 0.808511 (-490 335);
FORCEPROP 2 LASTPIN (-650 325) $PN 2
J 2
(-660 335);
DISPLAY 0.808511 (-660 335);
FORCEPROP 2 LAST TOLERANCE 20%
J 2
(-650 375);
DISPLAY 0.553191 (-650 375);
DISPLAY INVISIBLE (-650 375);
FORCEPROP 2 LAST PACK_TYPE C0201
J 2
(-750 375);
DISPLAY 0.553191 (-750 375);
DISPLAY INVISIBLE (-750 375);
FORCEPROP 1 LAST MATERIAL X6S
J 2
(-566 404);
DISPLAY 0.574468 (-566 404);
PAINT GREEN (-566 404);
DISPLAY INVISIBLE (-566 404);
FORCEPROP 2 LAST VOLTAGE 6.3V
J 2
(-925 375);
DISPLAY 0.553191 (-925 375);
DISPLAY INVISIBLE (-925 375);
FORCEPROP 1 LAST CDS_LMAN_SYM_OUTLINE -25,50,25,-50
J 2
(-575 325);
DISPLAY 0.468085 (-575 325);
PAINT GREEN (-575 325);
DISPLAY INVISIBLE (-575 325);
FORCEPROP 2 LAST CDS_LIB pure_quanta
J 2
(-575 325);
DISPLAY INVISIBLE (-575 325);
FORCEPROP 1 LAST PIN_NAMES_ROTATE TRUE
J 2
(-575 325);
DISPLAY 0.489362 (-575 325);
PAINT GREEN (-575 325);
DISPLAY INVISIBLE (-575 325);
FORCEPROP 1 LAST PATH I22
J 2
(-575 325);
DISPLAY 0.723404 (-575 325);
DISPLAY INVISIBLE (-575 325);
FORCEPROP 1 LAST $LOCATION C933
J 0
(-325 400);
DISPLAY 1.021277 (-325 400);
DISPLAY INVISIBLE (-325 400);
FORCEPROP 2 LAST CDS_LOCATION C933
J 0
(-325 400);
DISPLAY 1.021277 (-325 400);
DISPLAY INVISIBLE (-325 400);
FORCEPROP 2 LAST $SEC 1
J 2
(-400 400);
DISPLAY 0.680851 (-400 400);
PAINT MONO (-400 400);
DISPLAY INVISIBLE (-400 400);
FORCEPROP 2 LAST CDS_SEC 1
J 2
(-400 400);
DISPLAY 0.680851 (-400 400);
DISPLAY INVISIBLE (-400 400);
FORCEADD Q_CAP_DIFFBUS..2
R 2
(-575 525);
FORCEPROP 1 LAST PART_NUMBER SP_CH4221MEE01
J 2
(-691 613);
DISPLAY 0.574468 (-691 613);
PAINT GREEN (-691 613);
DISPLAY INVISIBLE (-691 613);
FORCEPROP 2 LAST VALUE DIFF BUS_0.22UF
J 2
(-725 525);
DISPLAY 0.553191 (-725 525);
FORCEPROP 1 LAST $LOCATION C931
J 2
(-341 542);
DISPLAY 0.723404 (-341 542);
PAINT GREEN (-341 542);
FORCEPROP 2 LASTPIN (-500 525) $PN 1
J 0
(-490 535);
DISPLAY 0.808511 (-490 535);
FORCEPROP 2 LASTPIN (-650 525) $PN 2
J 2
(-660 535);
DISPLAY 0.808511 (-660 535);
FORCEPROP 2 LAST TOLERANCE 20%
J 2
(-650 575);
DISPLAY 0.553191 (-650 575);
DISPLAY INVISIBLE (-650 575);
FORCEPROP 2 LAST PACK_TYPE C0201
J 2
(-750 575);
DISPLAY 0.553191 (-750 575);
DISPLAY INVISIBLE (-750 575);
FORCEPROP 1 LAST MATERIAL X6S
J 2
(-566 604);
DISPLAY 0.574468 (-566 604);
PAINT GREEN (-566 604);
DISPLAY INVISIBLE (-566 604);
FORCEPROP 2 LAST VOLTAGE 6.3V
J 2
(-925 575);
DISPLAY 0.553191 (-925 575);
DISPLAY INVISIBLE (-925 575);
FORCEPROP 1 LAST CDS_LMAN_SYM_OUTLINE -25,50,25,-50
J 2
(-575 525);
DISPLAY 0.468085 (-575 525);
PAINT GREEN (-575 525);
DISPLAY INVISIBLE (-575 525);
FORCEPROP 2 LAST CDS_LIB pure_quanta
J 2
(-575 525);
DISPLAY INVISIBLE (-575 525);
FORCEPROP 1 LAST PIN_NAMES_ROTATE TRUE
J 2
(-575 525);
DISPLAY 0.489362 (-575 525);
PAINT GREEN (-575 525);
DISPLAY INVISIBLE (-575 525);
FORCEPROP 1 LAST PATH I23
J 2
(-575 525);
DISPLAY 0.723404 (-575 525);
DISPLAY INVISIBLE (-575 525);
FORCEPROP 1 LAST $LOCATION C931
J 0
(-325 600);
DISPLAY 1.021277 (-325 600);
DISPLAY INVISIBLE (-325 600);
FORCEPROP 2 LAST CDS_LOCATION C931
J 0
(-325 600);
DISPLAY 1.021277 (-325 600);
DISPLAY INVISIBLE (-325 600);
FORCEPROP 2 LAST $SEC 1
J 2
(-400 600);
DISPLAY 0.680851 (-400 600);
PAINT MONO (-400 600);
DISPLAY INVISIBLE (-400 600);
FORCEPROP 2 LAST CDS_SEC 1
J 2
(-400 600);
DISPLAY 0.680851 (-400 600);
DISPLAY INVISIBLE (-400 600);
FORCEADD Q_CAP_DIFFBUS..2
R 2
(-575 575);
FORCEPROP 1 LAST PART_NUMBER SP_CH4221MEE01
J 2
(-691 663);
DISPLAY 0.574468 (-691 663);
PAINT GREEN (-691 663);
DISPLAY INVISIBLE (-691 663);
FORCEPROP 2 LAST VALUE DIFF BUS_0.22UF
J 2
(-725 575);
DISPLAY 0.553191 (-725 575);
FORCEPROP 1 LAST $LOCATION C930
J 2
(-341 592);
DISPLAY 0.723404 (-341 592);
PAINT GREEN (-341 592);
FORCEPROP 2 LASTPIN (-500 575) $PN 1
J 0
(-490 585);
DISPLAY 0.808511 (-490 585);
FORCEPROP 2 LASTPIN (-650 575) $PN 2
J 2
(-660 585);
DISPLAY 0.808511 (-660 585);
FORCEPROP 2 LAST TOLERANCE 20%
J 2
(-650 625);
DISPLAY 0.553191 (-650 625);
DISPLAY INVISIBLE (-650 625);
FORCEPROP 2 LAST PACK_TYPE C0201
J 2
(-750 625);
DISPLAY 0.553191 (-750 625);
DISPLAY INVISIBLE (-750 625);
FORCEPROP 1 LAST MATERIAL X6S
J 2
(-566 654);
DISPLAY 0.574468 (-566 654);
PAINT GREEN (-566 654);
DISPLAY INVISIBLE (-566 654);
FORCEPROP 2 LAST VOLTAGE 6.3V
J 2
(-925 625);
DISPLAY 0.553191 (-925 625);
DISPLAY INVISIBLE (-925 625);
FORCEPROP 2 LAST CDS_LIB pure_quanta
J 2
(-575 575);
DISPLAY INVISIBLE (-575 575);
FORCEPROP 1 LAST CDS_LMAN_SYM_OUTLINE -25,50,25,-50
J 2
(-575 575);
DISPLAY 0.468085 (-575 575);
PAINT GREEN (-575 575);
DISPLAY INVISIBLE (-575 575);
FORCEPROP 1 LAST PIN_NAMES_ROTATE TRUE
J 2
(-575 575);
DISPLAY 0.489362 (-575 575);
PAINT GREEN (-575 575);
DISPLAY INVISIBLE (-575 575);
FORCEPROP 1 LAST PATH I24
J 2
(-575 575);
DISPLAY 0.723404 (-575 575);
DISPLAY INVISIBLE (-575 575);
FORCEPROP 1 LAST $LOCATION C930
J 0
(-325 650);
DISPLAY 1.021277 (-325 650);
DISPLAY INVISIBLE (-325 650);
FORCEPROP 2 LAST CDS_LOCATION C930
J 0
(-325 650);
DISPLAY 1.021277 (-325 650);
DISPLAY INVISIBLE (-325 650);
FORCEPROP 2 LAST $SEC 1
J 2
(-400 650);
DISPLAY 0.680851 (-400 650);
PAINT MONO (-400 650);
DISPLAY INVISIBLE (-400 650);
FORCEPROP 2 LAST CDS_SEC 1
J 2
(-400 650);
DISPLAY 0.680851 (-400 650);
DISPLAY INVISIBLE (-400 650);
FORCEADD Q_CAP_DIFFBUS..2
R 2
(-575 775);
FORCEPROP 1 LAST PART_NUMBER SP_CH4221MEE01
J 2
(-691 863);
DISPLAY 0.574468 (-691 863);
PAINT GREEN (-691 863);
DISPLAY INVISIBLE (-691 863);
FORCEPROP 2 LAST VALUE DIFF BUS_0.22UF
J 2
(-725 775);
DISPLAY 0.553191 (-725 775);
FORCEPROP 1 LAST $LOCATION C928
J 2
(-341 792);
DISPLAY 0.723404 (-341 792);
PAINT GREEN (-341 792);
FORCEPROP 2 LASTPIN (-500 775) $PN 1
J 0
(-490 785);
DISPLAY 0.808511 (-490 785);
FORCEPROP 2 LASTPIN (-650 775) $PN 2
J 2
(-660 785);
DISPLAY 0.808511 (-660 785);
FORCEPROP 2 LAST TOLERANCE 20%
J 2
(-650 825);
DISPLAY 0.553191 (-650 825);
DISPLAY INVISIBLE (-650 825);
FORCEPROP 2 LAST PACK_TYPE C0201
J 2
(-750 825);
DISPLAY 0.553191 (-750 825);
DISPLAY INVISIBLE (-750 825);
FORCEPROP 1 LAST MATERIAL X6S
J 2
(-566 854);
DISPLAY 0.574468 (-566 854);
PAINT GREEN (-566 854);
DISPLAY INVISIBLE (-566 854);
FORCEPROP 2 LAST VOLTAGE 6.3V
J 2
(-925 825);
DISPLAY 0.553191 (-925 825);
DISPLAY INVISIBLE (-925 825);
FORCEPROP 1 LAST CDS_LMAN_SYM_OUTLINE -25,50,25,-50
J 2
(-575 775);
DISPLAY 0.468085 (-575 775);
PAINT GREEN (-575 775);
DISPLAY INVISIBLE (-575 775);
FORCEPROP 2 LAST CDS_LIB pure_quanta
J 2
(-575 775);
DISPLAY INVISIBLE (-575 775);
FORCEPROP 1 LAST PIN_NAMES_ROTATE TRUE
J 2
(-575 775);
DISPLAY 0.489362 (-575 775);
PAINT GREEN (-575 775);
DISPLAY INVISIBLE (-575 775);
FORCEPROP 1 LAST PATH I25
J 2
(-575 775);
DISPLAY 0.723404 (-575 775);
DISPLAY INVISIBLE (-575 775);
FORCEPROP 1 LAST $LOCATION C928
J 0
(-325 850);
DISPLAY 1.021277 (-325 850);
DISPLAY INVISIBLE (-325 850);
FORCEPROP 2 LAST CDS_LOCATION C928
J 0
(-325 850);
DISPLAY 1.021277 (-325 850);
DISPLAY INVISIBLE (-325 850);
FORCEPROP 2 LAST $SEC 1
J 2
(-400 850);
DISPLAY 0.680851 (-400 850);
PAINT MONO (-400 850);
DISPLAY INVISIBLE (-400 850);
FORCEPROP 2 LAST CDS_SEC 1
J 2
(-400 850);
DISPLAY 0.680851 (-400 850);
DISPLAY INVISIBLE (-400 850);
FORCEADD Q_CAP_DIFFBUS..2
R 2
(-575 725);
FORCEPROP 1 LAST PART_NUMBER SP_CH4221MEE01
J 2
(-691 813);
DISPLAY 0.574468 (-691 813);
PAINT GREEN (-691 813);
DISPLAY INVISIBLE (-691 813);
FORCEPROP 2 LAST VALUE DIFF BUS_0.22UF
J 2
(-725 725);
DISPLAY 0.553191 (-725 725);
FORCEPROP 1 LAST $LOCATION C929
J 2
(-341 742);
DISPLAY 0.723404 (-341 742);
PAINT GREEN (-341 742);
FORCEPROP 2 LASTPIN (-500 725) $PN 1
J 0
(-490 735);
DISPLAY 0.808511 (-490 735);
FORCEPROP 2 LASTPIN (-650 725) $PN 2
J 2
(-660 735);
DISPLAY 0.808511 (-660 735);
FORCEPROP 2 LAST TOLERANCE 20%
J 2
(-650 775);
DISPLAY 0.553191 (-650 775);
DISPLAY INVISIBLE (-650 775);
FORCEPROP 2 LAST PACK_TYPE C0201
J 2
(-750 775);
DISPLAY 0.553191 (-750 775);
DISPLAY INVISIBLE (-750 775);
FORCEPROP 1 LAST MATERIAL X6S
J 2
(-566 804);
DISPLAY 0.574468 (-566 804);
PAINT GREEN (-566 804);
DISPLAY INVISIBLE (-566 804);
FORCEPROP 2 LAST VOLTAGE 6.3V
J 2
(-925 775);
DISPLAY 0.553191 (-925 775);
DISPLAY INVISIBLE (-925 775);
FORCEPROP 1 LAST CDS_LMAN_SYM_OUTLINE -25,50,25,-50
J 2
(-575 725);
DISPLAY 0.468085 (-575 725);
PAINT GREEN (-575 725);
DISPLAY INVISIBLE (-575 725);
FORCEPROP 2 LAST CDS_LIB pure_quanta
J 2
(-575 725);
DISPLAY INVISIBLE (-575 725);
FORCEPROP 1 LAST PIN_NAMES_ROTATE TRUE
J 2
(-575 725);
DISPLAY 0.489362 (-575 725);
PAINT GREEN (-575 725);
DISPLAY INVISIBLE (-575 725);
FORCEPROP 1 LAST PATH I26
J 2
(-575 725);
DISPLAY 0.723404 (-575 725);
DISPLAY INVISIBLE (-575 725);
FORCEPROP 1 LAST $LOCATION C929
J 0
(-325 800);
DISPLAY 1.021277 (-325 800);
DISPLAY INVISIBLE (-325 800);
FORCEPROP 2 LAST CDS_LOCATION C929
J 0
(-325 800);
DISPLAY 1.021277 (-325 800);
DISPLAY INVISIBLE (-325 800);
FORCEPROP 2 LAST $SEC 1
J 2
(-400 800);
DISPLAY 0.680851 (-400 800);
PAINT MONO (-400 800);
DISPLAY INVISIBLE (-400 800);
FORCEPROP 2 LAST CDS_SEC 1
J 2
(-400 800);
DISPLAY 0.680851 (-400 800);
DISPLAY INVISIBLE (-400 800);
FORCEADD Q_CAP_DIFFBUS..2
R 2
(-575 925);
FORCEPROP 1 LAST PART_NUMBER SP_CH4221MEE01
J 2
(-691 1013);
DISPLAY 0.574468 (-691 1013);
PAINT GREEN (-691 1013);
DISPLAY INVISIBLE (-691 1013);
FORCEPROP 2 LAST VALUE DIFF BUS_0.22UF
J 2
(-725 925);
DISPLAY 0.553191 (-725 925);
FORCEPROP 1 LAST $LOCATION C927
J 2
(-341 942);
DISPLAY 0.723404 (-341 942);
PAINT GREEN (-341 942);
FORCEPROP 2 LASTPIN (-500 925) $PN 1
J 0
(-490 935);
DISPLAY 0.808511 (-490 935);
FORCEPROP 2 LASTPIN (-650 925) $PN 2
J 2
(-660 935);
DISPLAY 0.808511 (-660 935);
FORCEPROP 2 LAST TOLERANCE 20%
J 2
(-650 975);
DISPLAY 0.553191 (-650 975);
DISPLAY INVISIBLE (-650 975);
FORCEPROP 2 LAST PACK_TYPE C0201
J 2
(-750 975);
DISPLAY 0.553191 (-750 975);
DISPLAY INVISIBLE (-750 975);
FORCEPROP 1 LAST MATERIAL X6S
J 2
(-566 1004);
DISPLAY 0.574468 (-566 1004);
PAINT GREEN (-566 1004);
DISPLAY INVISIBLE (-566 1004);
FORCEPROP 2 LAST VOLTAGE 6.3V
J 2
(-925 975);
DISPLAY 0.553191 (-925 975);
DISPLAY INVISIBLE (-925 975);
FORCEPROP 2 LAST CDS_LIB pure_quanta
J 2
(-575 925);
DISPLAY INVISIBLE (-575 925);
FORCEPROP 1 LAST CDS_LMAN_SYM_OUTLINE -25,50,25,-50
J 2
(-575 925);
DISPLAY 0.468085 (-575 925);
PAINT GREEN (-575 925);
DISPLAY INVISIBLE (-575 925);
FORCEPROP 1 LAST PIN_NAMES_ROTATE TRUE
J 2
(-575 925);
DISPLAY 0.489362 (-575 925);
PAINT GREEN (-575 925);
DISPLAY INVISIBLE (-575 925);
FORCEPROP 1 LAST PATH I27
J 2
(-575 925);
DISPLAY 0.723404 (-575 925);
DISPLAY INVISIBLE (-575 925);
FORCEPROP 1 LAST $LOCATION C927
J 0
(-325 1000);
DISPLAY 1.021277 (-325 1000);
DISPLAY INVISIBLE (-325 1000);
FORCEPROP 2 LAST CDS_LOCATION C927
J 0
(-325 1000);
DISPLAY 1.021277 (-325 1000);
DISPLAY INVISIBLE (-325 1000);
FORCEPROP 2 LAST $SEC 1
J 2
(-400 1000);
DISPLAY 0.680851 (-400 1000);
PAINT MONO (-400 1000);
DISPLAY INVISIBLE (-400 1000);
FORCEPROP 2 LAST CDS_SEC 1
J 2
(-400 1000);
DISPLAY 0.680851 (-400 1000);
DISPLAY INVISIBLE (-400 1000);
FORCEADD Q_CAP_DIFFBUS..2
R 2
(-575 975);
FORCEPROP 1 LAST PART_NUMBER SP_CH4221MEE01
J 2
(-691 1063);
DISPLAY 0.574468 (-691 1063);
PAINT GREEN (-691 1063);
DISPLAY INVISIBLE (-691 1063);
FORCEPROP 2 LAST VALUE DIFF BUS_0.22UF
J 2
(-725 975);
DISPLAY 0.553191 (-725 975);
FORCEPROP 1 LAST $LOCATION C926
J 2
(-341 992);
DISPLAY 0.723404 (-341 992);
PAINT GREEN (-341 992);
FORCEPROP 2 LASTPIN (-500 975) $PN 1
J 0
(-490 985);
DISPLAY 0.808511 (-490 985);
FORCEPROP 2 LASTPIN (-650 975) $PN 2
J 2
(-660 985);
DISPLAY 0.808511 (-660 985);
FORCEPROP 2 LAST TOLERANCE 20%
J 2
(-650 1025);
DISPLAY 0.553191 (-650 1025);
DISPLAY INVISIBLE (-650 1025);
FORCEPROP 2 LAST PACK_TYPE C0201
J 2
(-750 1025);
DISPLAY 0.553191 (-750 1025);
DISPLAY INVISIBLE (-750 1025);
FORCEPROP 1 LAST MATERIAL X6S
J 2
(-566 1054);
DISPLAY 0.574468 (-566 1054);
PAINT GREEN (-566 1054);
DISPLAY INVISIBLE (-566 1054);
FORCEPROP 2 LAST VOLTAGE 6.3V
J 2
(-925 1025);
DISPLAY 0.553191 (-925 1025);
DISPLAY INVISIBLE (-925 1025);
FORCEPROP 2 LAST CDS_LIB pure_quanta
J 2
(-575 975);
DISPLAY INVISIBLE (-575 975);
FORCEPROP 1 LAST CDS_LMAN_SYM_OUTLINE -25,50,25,-50
J 2
(-575 975);
DISPLAY 0.468085 (-575 975);
PAINT GREEN (-575 975);
DISPLAY INVISIBLE (-575 975);
FORCEPROP 1 LAST PIN_NAMES_ROTATE TRUE
J 2
(-575 975);
DISPLAY 0.489362 (-575 975);
PAINT GREEN (-575 975);
DISPLAY INVISIBLE (-575 975);
FORCEPROP 1 LAST PATH I28
J 2
(-575 975);
DISPLAY 0.723404 (-575 975);
DISPLAY INVISIBLE (-575 975);
FORCEPROP 1 LAST $LOCATION C926
J 0
(-325 1050);
DISPLAY 1.021277 (-325 1050);
DISPLAY INVISIBLE (-325 1050);
FORCEPROP 2 LAST CDS_LOCATION C926
J 0
(-325 1050);
DISPLAY 1.021277 (-325 1050);
DISPLAY INVISIBLE (-325 1050);
FORCEPROP 2 LAST $SEC 1
J 2
(-400 1050);
DISPLAY 0.680851 (-400 1050);
PAINT MONO (-400 1050);
DISPLAY INVISIBLE (-400 1050);
FORCEPROP 2 LAST CDS_SEC 1
J 2
(-400 1050);
DISPLAY 0.680851 (-400 1050);
DISPLAY INVISIBLE (-400 1050);
FORCEADD Q_CAP_DIFFBUS..2
R 2
(-575 1125);
FORCEPROP 1 LAST PART_NUMBER SP_CH4221MEE01
J 2
(-691 1213);
DISPLAY 0.574468 (-691 1213);
PAINT GREEN (-691 1213);
DISPLAY INVISIBLE (-691 1213);
FORCEPROP 2 LAST VALUE DIFF BUS_0.22UF
J 2
(-725 1125);
DISPLAY 0.553191 (-725 1125);
FORCEPROP 1 LAST $LOCATION C925
J 2
(-341 1142);
DISPLAY 0.723404 (-341 1142);
PAINT GREEN (-341 1142);
FORCEPROP 2 LASTPIN (-500 1125) $PN 1
J 0
(-490 1135);
DISPLAY 0.808511 (-490 1135);
FORCEPROP 2 LASTPIN (-650 1125) $PN 2
J 2
(-660 1135);
DISPLAY 0.808511 (-660 1135);
FORCEPROP 2 LAST TOLERANCE 20%
J 2
(-650 1175);
DISPLAY 0.553191 (-650 1175);
DISPLAY INVISIBLE (-650 1175);
FORCEPROP 2 LAST PACK_TYPE C0201
J 2
(-750 1175);
DISPLAY 0.553191 (-750 1175);
DISPLAY INVISIBLE (-750 1175);
FORCEPROP 1 LAST MATERIAL X6S
J 2
(-566 1204);
DISPLAY 0.574468 (-566 1204);
PAINT GREEN (-566 1204);
DISPLAY INVISIBLE (-566 1204);
FORCEPROP 2 LAST VOLTAGE 6.3V
J 2
(-925 1175);
DISPLAY 0.553191 (-925 1175);
DISPLAY INVISIBLE (-925 1175);
FORCEPROP 1 LAST CDS_LMAN_SYM_OUTLINE -25,50,25,-50
J 2
(-575 1125);
DISPLAY 0.468085 (-575 1125);
PAINT GREEN (-575 1125);
DISPLAY INVISIBLE (-575 1125);
FORCEPROP 2 LAST CDS_LIB pure_quanta
J 2
(-575 1125);
DISPLAY INVISIBLE (-575 1125);
FORCEPROP 1 LAST PIN_NAMES_ROTATE TRUE
J 2
(-575 1125);
DISPLAY 0.489362 (-575 1125);
PAINT GREEN (-575 1125);
DISPLAY INVISIBLE (-575 1125);
FORCEPROP 1 LAST PATH I29
J 2
(-575 1125);
DISPLAY 0.723404 (-575 1125);
DISPLAY INVISIBLE (-575 1125);
FORCEPROP 1 LAST $LOCATION C925
J 0
(-325 1200);
DISPLAY 1.021277 (-325 1200);
DISPLAY INVISIBLE (-325 1200);
FORCEPROP 2 LAST CDS_LOCATION C925
J 0
(-325 1200);
DISPLAY 1.021277 (-325 1200);
DISPLAY INVISIBLE (-325 1200);
FORCEPROP 2 LAST $SEC 1
J 2
(-400 1200);
DISPLAY 0.680851 (-400 1200);
PAINT MONO (-400 1200);
DISPLAY INVISIBLE (-400 1200);
FORCEPROP 2 LAST CDS_SEC 1
J 2
(-400 1200);
DISPLAY 0.680851 (-400 1200);
DISPLAY INVISIBLE (-400 1200);
FORCEADD OFFPAGE..1
(-2500 3725);
FORCEPROP 2 LAST $XR0 29 
J 0
(-2751 3725);
DISPLAY 0.638298 (-2751 3725);
PAINT MONO (-2751 3725);
FORCEPROP 2 LAST CDS_LIB standard
J 0
(-2500 3725);
DISPLAY INVISIBLE (-2500 3725);
FORCEPROP 1 LAST OFFPAGE TRUE
J 0
(-2175 3600);
DISPLAY 0.872340 (-2175 3600);
DISPLAY INVISIBLE (-2175 3600);
FORCEPROP 1 LAST COMMENT_BODY TRUE
J 0
(-2375 3625);
DISPLAY 0.872340 (-2375 3625);
PAINT GREEN (-2375 3625);
DISPLAY INVISIBLE (-2375 3625);
FORCEPROP 2 LAST PATH I3
J 0
(-2775 3775);
DISPLAY 1.021277 (-2775 3775);
DISPLAY INVISIBLE (-2775 3775);
FORCEADD Q_CAP_DIFFBUS..2
R 2
(-575 1175);
FORCEPROP 1 LAST PART_NUMBER SP_CH4221MEE01
J 2
(-691 1263);
DISPLAY 0.574468 (-691 1263);
PAINT GREEN (-691 1263);
DISPLAY INVISIBLE (-691 1263);
FORCEPROP 2 LAST VALUE DIFF BUS_0.22UF
J 2
(-725 1175);
DISPLAY 0.553191 (-725 1175);
FORCEPROP 1 LAST $LOCATION C924
J 2
(-341 1192);
DISPLAY 0.723404 (-341 1192);
PAINT GREEN (-341 1192);
FORCEPROP 2 LASTPIN (-500 1175) $PN 1
J 0
(-490 1185);
DISPLAY 0.808511 (-490 1185);
FORCEPROP 2 LASTPIN (-650 1175) $PN 2
J 2
(-660 1185);
DISPLAY 0.808511 (-660 1185);
FORCEPROP 2 LAST TOLERANCE 20%
J 2
(-650 1225);
DISPLAY 0.553191 (-650 1225);
DISPLAY INVISIBLE (-650 1225);
FORCEPROP 2 LAST PACK_TYPE C0201
J 2
(-750 1225);
DISPLAY 0.553191 (-750 1225);
DISPLAY INVISIBLE (-750 1225);
FORCEPROP 1 LAST MATERIAL X6S
J 2
(-566 1254);
DISPLAY 0.574468 (-566 1254);
PAINT GREEN (-566 1254);
DISPLAY INVISIBLE (-566 1254);
FORCEPROP 2 LAST VOLTAGE 6.3V
J 2
(-925 1225);
DISPLAY 0.553191 (-925 1225);
DISPLAY INVISIBLE (-925 1225);
FORCEPROP 1 LAST CDS_LMAN_SYM_OUTLINE -25,50,25,-50
J 2
(-575 1175);
DISPLAY 0.468085 (-575 1175);
PAINT GREEN (-575 1175);
DISPLAY INVISIBLE (-575 1175);
FORCEPROP 2 LAST CDS_LIB pure_quanta
J 2
(-575 1175);
DISPLAY INVISIBLE (-575 1175);
FORCEPROP 1 LAST PIN_NAMES_ROTATE TRUE
J 2
(-575 1175);
DISPLAY 0.489362 (-575 1175);
PAINT GREEN (-575 1175);
DISPLAY INVISIBLE (-575 1175);
FORCEPROP 1 LAST PATH I30
J 2
(-575 1175);
DISPLAY 0.723404 (-575 1175);
DISPLAY INVISIBLE (-575 1175);
FORCEPROP 1 LAST $LOCATION C924
J 0
(-325 1250);
DISPLAY 1.021277 (-325 1250);
DISPLAY INVISIBLE (-325 1250);
FORCEPROP 2 LAST CDS_LOCATION C924
J 0
(-325 1250);
DISPLAY 1.021277 (-325 1250);
DISPLAY INVISIBLE (-325 1250);
FORCEPROP 2 LAST $SEC 1
J 2
(-400 1250);
DISPLAY 0.680851 (-400 1250);
PAINT MONO (-400 1250);
DISPLAY INVISIBLE (-400 1250);
FORCEPROP 2 LAST CDS_SEC 1
J 2
(-400 1250);
DISPLAY 0.680851 (-400 1250);
DISPLAY INVISIBLE (-400 1250);
FORCEADD Q_CAP_DIFFBUS..2
R 2
(-575 1325);
FORCEPROP 1 LAST PART_NUMBER SP_CH4221MEE01
J 2
(-691 1413);
DISPLAY 0.574468 (-691 1413);
PAINT GREEN (-691 1413);
DISPLAY INVISIBLE (-691 1413);
FORCEPROP 2 LAST VALUE DIFF BUS_0.22UF
J 2
(-725 1325);
DISPLAY 0.553191 (-725 1325);
FORCEPROP 1 LAST $LOCATION C923
J 2
(-341 1342);
DISPLAY 0.723404 (-341 1342);
PAINT GREEN (-341 1342);
FORCEPROP 2 LASTPIN (-500 1325) $PN 1
J 0
(-490 1335);
DISPLAY 0.808511 (-490 1335);
FORCEPROP 2 LASTPIN (-650 1325) $PN 2
J 2
(-660 1335);
DISPLAY 0.808511 (-660 1335);
FORCEPROP 2 LAST TOLERANCE 20%
J 2
(-650 1375);
DISPLAY 0.553191 (-650 1375);
DISPLAY INVISIBLE (-650 1375);
FORCEPROP 2 LAST PACK_TYPE C0201
J 2
(-750 1375);
DISPLAY 0.553191 (-750 1375);
DISPLAY INVISIBLE (-750 1375);
FORCEPROP 1 LAST MATERIAL X6S
J 2
(-566 1404);
DISPLAY 0.574468 (-566 1404);
PAINT GREEN (-566 1404);
DISPLAY INVISIBLE (-566 1404);
FORCEPROP 2 LAST VOLTAGE 6.3V
J 2
(-925 1375);
DISPLAY 0.553191 (-925 1375);
DISPLAY INVISIBLE (-925 1375);
FORCEPROP 1 LAST CDS_LMAN_SYM_OUTLINE -25,50,25,-50
J 2
(-575 1325);
DISPLAY 0.468085 (-575 1325);
PAINT GREEN (-575 1325);
DISPLAY INVISIBLE (-575 1325);
FORCEPROP 2 LAST CDS_LIB pure_quanta
J 2
(-575 1325);
DISPLAY INVISIBLE (-575 1325);
FORCEPROP 1 LAST PIN_NAMES_ROTATE TRUE
J 2
(-575 1325);
DISPLAY 0.489362 (-575 1325);
PAINT GREEN (-575 1325);
DISPLAY INVISIBLE (-575 1325);
FORCEPROP 1 LAST PATH I31
J 2
(-575 1325);
DISPLAY 0.723404 (-575 1325);
DISPLAY INVISIBLE (-575 1325);
FORCEPROP 1 LAST $LOCATION C923
J 0
(-325 1400);
DISPLAY 1.021277 (-325 1400);
DISPLAY INVISIBLE (-325 1400);
FORCEPROP 2 LAST CDS_LOCATION C923
J 0
(-325 1400);
DISPLAY 1.021277 (-325 1400);
DISPLAY INVISIBLE (-325 1400);
FORCEPROP 2 LAST $SEC 1
J 2
(-400 1400);
DISPLAY 0.680851 (-400 1400);
PAINT MONO (-400 1400);
DISPLAY INVISIBLE (-400 1400);
FORCEPROP 2 LAST CDS_SEC 1
J 2
(-400 1400);
DISPLAY 0.680851 (-400 1400);
DISPLAY INVISIBLE (-400 1400);
FORCEADD Q_CAP_DIFFBUS..2
R 2
(-575 1375);
FORCEPROP 1 LAST PART_NUMBER SP_CH4221MEE01
J 2
(-691 1463);
DISPLAY 0.574468 (-691 1463);
PAINT GREEN (-691 1463);
DISPLAY INVISIBLE (-691 1463);
FORCEPROP 2 LAST VALUE DIFF BUS_0.22UF
J 2
(-725 1375);
DISPLAY 0.553191 (-725 1375);
FORCEPROP 1 LAST $LOCATION C922
J 2
(-341 1392);
DISPLAY 0.723404 (-341 1392);
PAINT GREEN (-341 1392);
FORCEPROP 2 LASTPIN (-500 1375) $PN 1
J 0
(-490 1385);
DISPLAY 0.808511 (-490 1385);
FORCEPROP 2 LASTPIN (-650 1375) $PN 2
J 2
(-660 1385);
DISPLAY 0.808511 (-660 1385);
FORCEPROP 2 LAST TOLERANCE 20%
J 2
(-650 1425);
DISPLAY 0.553191 (-650 1425);
DISPLAY INVISIBLE (-650 1425);
FORCEPROP 2 LAST PACK_TYPE C0201
J 2
(-750 1425);
DISPLAY 0.553191 (-750 1425);
DISPLAY INVISIBLE (-750 1425);
FORCEPROP 1 LAST MATERIAL X6S
J 2
(-566 1454);
DISPLAY 0.574468 (-566 1454);
PAINT GREEN (-566 1454);
DISPLAY INVISIBLE (-566 1454);
FORCEPROP 2 LAST VOLTAGE 6.3V
J 2
(-925 1425);
DISPLAY 0.553191 (-925 1425);
DISPLAY INVISIBLE (-925 1425);
FORCEPROP 1 LAST CDS_LMAN_SYM_OUTLINE -25,50,25,-50
J 2
(-575 1375);
DISPLAY 0.468085 (-575 1375);
PAINT GREEN (-575 1375);
DISPLAY INVISIBLE (-575 1375);
FORCEPROP 2 LAST CDS_LIB pure_quanta
J 2
(-575 1375);
DISPLAY INVISIBLE (-575 1375);
FORCEPROP 1 LAST PIN_NAMES_ROTATE TRUE
J 2
(-575 1375);
DISPLAY 0.489362 (-575 1375);
PAINT GREEN (-575 1375);
DISPLAY INVISIBLE (-575 1375);
FORCEPROP 1 LAST PATH I32
J 2
(-575 1375);
DISPLAY 0.723404 (-575 1375);
DISPLAY INVISIBLE (-575 1375);
FORCEPROP 1 LAST $LOCATION C922
J 0
(-325 1450);
DISPLAY 1.021277 (-325 1450);
DISPLAY INVISIBLE (-325 1450);
FORCEPROP 2 LAST CDS_LOCATION C922
J 0
(-325 1450);
DISPLAY 1.021277 (-325 1450);
DISPLAY INVISIBLE (-325 1450);
FORCEPROP 2 LAST $SEC 1
J 2
(-400 1450);
DISPLAY 0.680851 (-400 1450);
PAINT MONO (-400 1450);
DISPLAY INVISIBLE (-400 1450);
FORCEPROP 2 LAST CDS_SEC 1
J 2
(-400 1450);
DISPLAY 0.680851 (-400 1450);
DISPLAY INVISIBLE (-400 1450);
FORCEADD Q_CAP_DIFFBUS..2
R 2
(-575 1525);
FORCEPROP 1 LAST PART_NUMBER SP_CH4221MEE01
J 2
(-691 1613);
DISPLAY 0.574468 (-691 1613);
PAINT GREEN (-691 1613);
DISPLAY INVISIBLE (-691 1613);
FORCEPROP 2 LAST VALUE DIFF BUS_0.22UF
J 2
(-725 1525);
DISPLAY 0.553191 (-725 1525);
FORCEPROP 1 LAST $LOCATION C921
J 2
(-341 1542);
DISPLAY 0.723404 (-341 1542);
PAINT GREEN (-341 1542);
FORCEPROP 2 LASTPIN (-500 1525) $PN 1
J 0
(-490 1535);
DISPLAY 0.808511 (-490 1535);
FORCEPROP 2 LASTPIN (-650 1525) $PN 2
J 2
(-660 1535);
DISPLAY 0.808511 (-660 1535);
FORCEPROP 2 LAST TOLERANCE 20%
J 2
(-650 1575);
DISPLAY 0.553191 (-650 1575);
DISPLAY INVISIBLE (-650 1575);
FORCEPROP 2 LAST PACK_TYPE C0201
J 2
(-750 1575);
DISPLAY 0.553191 (-750 1575);
DISPLAY INVISIBLE (-750 1575);
FORCEPROP 1 LAST MATERIAL X6S
J 2
(-566 1604);
DISPLAY 0.574468 (-566 1604);
PAINT GREEN (-566 1604);
DISPLAY INVISIBLE (-566 1604);
FORCEPROP 2 LAST VOLTAGE 6.3V
J 2
(-925 1575);
DISPLAY 0.553191 (-925 1575);
DISPLAY INVISIBLE (-925 1575);
FORCEPROP 1 LAST CDS_LMAN_SYM_OUTLINE -25,50,25,-50
J 2
(-575 1525);
DISPLAY 0.468085 (-575 1525);
PAINT GREEN (-575 1525);
DISPLAY INVISIBLE (-575 1525);
FORCEPROP 2 LAST CDS_LIB pure_quanta
J 2
(-575 1525);
DISPLAY INVISIBLE (-575 1525);
FORCEPROP 1 LAST PIN_NAMES_ROTATE TRUE
J 2
(-575 1525);
DISPLAY 0.489362 (-575 1525);
PAINT GREEN (-575 1525);
DISPLAY INVISIBLE (-575 1525);
FORCEPROP 1 LAST PATH I33
J 2
(-575 1525);
DISPLAY 0.723404 (-575 1525);
DISPLAY INVISIBLE (-575 1525);
FORCEPROP 1 LAST $LOCATION C921
J 0
(-325 1600);
DISPLAY 1.021277 (-325 1600);
DISPLAY INVISIBLE (-325 1600);
FORCEPROP 2 LAST CDS_LOCATION C921
J 0
(-325 1600);
DISPLAY 1.021277 (-325 1600);
DISPLAY INVISIBLE (-325 1600);
FORCEPROP 2 LAST $SEC 1
J 2
(-400 1600);
DISPLAY 0.680851 (-400 1600);
PAINT MONO (-400 1600);
DISPLAY INVISIBLE (-400 1600);
FORCEPROP 2 LAST CDS_SEC 1
J 2
(-400 1600);
DISPLAY 0.680851 (-400 1600);
DISPLAY INVISIBLE (-400 1600);
FORCEADD Q_CAP_DIFFBUS..2
R 2
(-575 1575);
FORCEPROP 1 LAST PART_NUMBER SP_CH4221MEE01
J 2
(-691 1663);
DISPLAY 0.574468 (-691 1663);
PAINT GREEN (-691 1663);
DISPLAY INVISIBLE (-691 1663);
FORCEPROP 2 LAST VALUE DIFF BUS_0.22UF
J 2
(-725 1575);
DISPLAY 0.553191 (-725 1575);
FORCEPROP 1 LAST $LOCATION C920
J 2
(-341 1592);
DISPLAY 0.723404 (-341 1592);
PAINT GREEN (-341 1592);
FORCEPROP 2 LASTPIN (-500 1575) $PN 1
J 0
(-490 1585);
DISPLAY 0.808511 (-490 1585);
FORCEPROP 2 LASTPIN (-650 1575) $PN 2
J 2
(-660 1585);
DISPLAY 0.808511 (-660 1585);
FORCEPROP 2 LAST TOLERANCE 20%
J 2
(-650 1625);
DISPLAY 0.553191 (-650 1625);
DISPLAY INVISIBLE (-650 1625);
FORCEPROP 2 LAST PACK_TYPE C0201
J 2
(-750 1625);
DISPLAY 0.553191 (-750 1625);
DISPLAY INVISIBLE (-750 1625);
FORCEPROP 1 LAST MATERIAL X6S
J 2
(-566 1654);
DISPLAY 0.574468 (-566 1654);
PAINT GREEN (-566 1654);
DISPLAY INVISIBLE (-566 1654);
FORCEPROP 2 LAST VOLTAGE 6.3V
J 2
(-925 1625);
DISPLAY 0.553191 (-925 1625);
DISPLAY INVISIBLE (-925 1625);
FORCEPROP 1 LAST CDS_LMAN_SYM_OUTLINE -25,50,25,-50
J 2
(-575 1575);
DISPLAY 0.468085 (-575 1575);
PAINT GREEN (-575 1575);
DISPLAY INVISIBLE (-575 1575);
FORCEPROP 2 LAST CDS_LIB pure_quanta
J 2
(-575 1575);
DISPLAY INVISIBLE (-575 1575);
FORCEPROP 1 LAST PIN_NAMES_ROTATE TRUE
J 2
(-575 1575);
DISPLAY 0.489362 (-575 1575);
PAINT GREEN (-575 1575);
DISPLAY INVISIBLE (-575 1575);
FORCEPROP 1 LAST PATH I34
J 2
(-575 1575);
DISPLAY 0.723404 (-575 1575);
DISPLAY INVISIBLE (-575 1575);
FORCEPROP 1 LAST $LOCATION C920
J 0
(-325 1650);
DISPLAY 1.021277 (-325 1650);
DISPLAY INVISIBLE (-325 1650);
FORCEPROP 2 LAST CDS_LOCATION C920
J 0
(-325 1650);
DISPLAY 1.021277 (-325 1650);
DISPLAY INVISIBLE (-325 1650);
FORCEPROP 2 LAST $SEC 1
J 2
(-400 1650);
DISPLAY 0.680851 (-400 1650);
PAINT MONO (-400 1650);
DISPLAY INVISIBLE (-400 1650);
FORCEPROP 2 LAST CDS_SEC 1
J 2
(-400 1650);
DISPLAY 0.680851 (-400 1650);
DISPLAY INVISIBLE (-400 1650);
FORCEADD Q_CAP_DIFFBUS..2
R 2
(-575 1775);
FORCEPROP 1 LAST PART_NUMBER SP_CH4221MEE01
J 2
(-691 1863);
DISPLAY 0.574468 (-691 1863);
PAINT GREEN (-691 1863);
DISPLAY INVISIBLE (-691 1863);
FORCEPROP 2 LAST VALUE DIFF BUS_0.22UF
J 2
(-725 1775);
DISPLAY 0.553191 (-725 1775);
FORCEPROP 1 LAST $LOCATION C918
J 2
(-341 1792);
DISPLAY 0.723404 (-341 1792);
PAINT GREEN (-341 1792);
FORCEPROP 2 LASTPIN (-500 1775) $PN 1
J 0
(-490 1785);
DISPLAY 0.808511 (-490 1785);
FORCEPROP 2 LASTPIN (-650 1775) $PN 2
J 2
(-660 1785);
DISPLAY 0.808511 (-660 1785);
FORCEPROP 2 LAST TOLERANCE 20%
J 2
(-650 1825);
DISPLAY 0.553191 (-650 1825);
DISPLAY INVISIBLE (-650 1825);
FORCEPROP 2 LAST PACK_TYPE C0201
J 2
(-750 1825);
DISPLAY 0.553191 (-750 1825);
DISPLAY INVISIBLE (-750 1825);
FORCEPROP 1 LAST MATERIAL X6S
J 2
(-566 1854);
DISPLAY 0.574468 (-566 1854);
PAINT GREEN (-566 1854);
DISPLAY INVISIBLE (-566 1854);
FORCEPROP 2 LAST VOLTAGE 6.3V
J 2
(-925 1825);
DISPLAY 0.553191 (-925 1825);
DISPLAY INVISIBLE (-925 1825);
FORCEPROP 2 LAST CDS_LIB pure_quanta
J 2
(-575 1775);
DISPLAY INVISIBLE (-575 1775);
FORCEPROP 1 LAST CDS_LMAN_SYM_OUTLINE -25,50,25,-50
J 2
(-575 1775);
DISPLAY 0.468085 (-575 1775);
PAINT GREEN (-575 1775);
DISPLAY INVISIBLE (-575 1775);
FORCEPROP 1 LAST PIN_NAMES_ROTATE TRUE
J 2
(-575 1775);
DISPLAY 0.489362 (-575 1775);
PAINT GREEN (-575 1775);
DISPLAY INVISIBLE (-575 1775);
FORCEPROP 1 LAST PATH I35
J 2
(-575 1775);
DISPLAY 0.723404 (-575 1775);
DISPLAY INVISIBLE (-575 1775);
FORCEPROP 1 LAST $LOCATION C918
J 0
(-325 1850);
DISPLAY 1.021277 (-325 1850);
DISPLAY INVISIBLE (-325 1850);
FORCEPROP 2 LAST CDS_LOCATION C918
J 0
(-325 1850);
DISPLAY 1.021277 (-325 1850);
DISPLAY INVISIBLE (-325 1850);
FORCEPROP 2 LAST $SEC 1
J 2
(-400 1850);
DISPLAY 0.680851 (-400 1850);
PAINT MONO (-400 1850);
DISPLAY INVISIBLE (-400 1850);
FORCEPROP 2 LAST CDS_SEC 1
J 2
(-400 1850);
DISPLAY 0.680851 (-400 1850);
DISPLAY INVISIBLE (-400 1850);
FORCEADD Q_CAP_DIFFBUS..2
R 2
(-575 1725);
FORCEPROP 1 LAST PART_NUMBER SP_CH4221MEE01
J 2
(-691 1813);
DISPLAY 0.574468 (-691 1813);
PAINT GREEN (-691 1813);
DISPLAY INVISIBLE (-691 1813);
FORCEPROP 2 LAST VALUE DIFF BUS_0.22UF
J 2
(-725 1725);
DISPLAY 0.553191 (-725 1725);
FORCEPROP 1 LAST $LOCATION C919
J 2
(-341 1742);
DISPLAY 0.723404 (-341 1742);
PAINT GREEN (-341 1742);
FORCEPROP 2 LASTPIN (-500 1725) $PN 1
J 0
(-490 1735);
DISPLAY 0.808511 (-490 1735);
FORCEPROP 2 LASTPIN (-650 1725) $PN 2
J 2
(-660 1735);
DISPLAY 0.808511 (-660 1735);
FORCEPROP 2 LAST TOLERANCE 20%
J 2
(-650 1775);
DISPLAY 0.553191 (-650 1775);
DISPLAY INVISIBLE (-650 1775);
FORCEPROP 2 LAST PACK_TYPE C0201
J 2
(-750 1775);
DISPLAY 0.553191 (-750 1775);
DISPLAY INVISIBLE (-750 1775);
FORCEPROP 1 LAST MATERIAL X6S
J 2
(-566 1804);
DISPLAY 0.574468 (-566 1804);
PAINT GREEN (-566 1804);
DISPLAY INVISIBLE (-566 1804);
FORCEPROP 2 LAST VOLTAGE 6.3V
J 2
(-925 1775);
DISPLAY 0.553191 (-925 1775);
DISPLAY INVISIBLE (-925 1775);
FORCEPROP 1 LAST CDS_LMAN_SYM_OUTLINE -25,50,25,-50
J 2
(-575 1725);
DISPLAY 0.468085 (-575 1725);
PAINT GREEN (-575 1725);
DISPLAY INVISIBLE (-575 1725);
FORCEPROP 2 LAST CDS_LIB pure_quanta
J 2
(-575 1725);
DISPLAY INVISIBLE (-575 1725);
FORCEPROP 1 LAST PIN_NAMES_ROTATE TRUE
J 2
(-575 1725);
DISPLAY 0.489362 (-575 1725);
PAINT GREEN (-575 1725);
DISPLAY INVISIBLE (-575 1725);
FORCEPROP 1 LAST PATH I36
J 2
(-575 1725);
DISPLAY 0.723404 (-575 1725);
DISPLAY INVISIBLE (-575 1725);
FORCEPROP 1 LAST $LOCATION C919
J 0
(-325 1800);
DISPLAY 1.021277 (-325 1800);
DISPLAY INVISIBLE (-325 1800);
FORCEPROP 2 LAST CDS_LOCATION C919
J 0
(-325 1800);
DISPLAY 1.021277 (-325 1800);
DISPLAY INVISIBLE (-325 1800);
FORCEPROP 2 LAST $SEC 1
J 2
(-400 1800);
DISPLAY 0.680851 (-400 1800);
PAINT MONO (-400 1800);
DISPLAY INVISIBLE (-400 1800);
FORCEPROP 2 LAST CDS_SEC 1
J 2
(-400 1800);
DISPLAY 0.680851 (-400 1800);
DISPLAY INVISIBLE (-400 1800);
FORCEADD TAP..1
R 2
(-1550 2300);
FORCEPROP 3 LASTPIN (-1500 2300) SIG_NAME P5E_CPU0_PE0_TX_DP<8>
J 0
(-1490 2310);
DISPLAY 0.659574 (-1490 2310);
PAINT MONO (-1490 2310);
DISPLAY INVISIBLE (-1490 2310);
FORCEPROP 1 LASTPIN (-1500 2300) BN 8
J 2
(-1488 2308);
DISPLAY 0.680851 (-1488 2308);
PAINT GREEN (-1488 2308);
FORCEPROP 2 LAST CDS_LIB standard
J 0
(-1550 2300);
DISPLAY INVISIBLE (-1550 2300);
FORCEPROP 1 LAST BODY_TYPE PLUMBING
J 2
(-1550 2350);
DISPLAY 0.872340 (-1550 2350);
PAINT GREEN (-1550 2350);
DISPLAY INVISIBLE (-1550 2350);
FORCEPROP 1 LAST HDL_TAP TRUE
J 2
(-1875 2175);
DISPLAY 0.872340 (-1875 2175);
DISPLAY INVISIBLE (-1875 2175);
FORCEPROP 1 LAST PATH I37
J 2
(-1548 2300);
DISPLAY 0.872340 (-1548 2300);
PAINT GREEN (-1548 2300);
DISPLAY INVISIBLE (-1548 2300);
FORCEADD TAP..1
R 2
(-1550 2500);
FORCEPROP 3 LASTPIN (-1500 2500) SIG_NAME P5E_CPU0_PE0_TX_DP<9>
J 0
(-1490 2510);
DISPLAY 0.659574 (-1490 2510);
PAINT MONO (-1490 2510);
DISPLAY INVISIBLE (-1490 2510);
FORCEPROP 1 LASTPIN (-1500 2500) BN 9
J 2
(-1488 2508);
DISPLAY 0.680851 (-1488 2508);
PAINT GREEN (-1488 2508);
FORCEPROP 2 LAST CDS_LIB standard
J 0
(-1550 2500);
DISPLAY INVISIBLE (-1550 2500);
FORCEPROP 1 LAST BODY_TYPE PLUMBING
J 2
(-1550 2550);
DISPLAY 0.872340 (-1550 2550);
PAINT GREEN (-1550 2550);
DISPLAY INVISIBLE (-1550 2550);
FORCEPROP 1 LAST HDL_TAP TRUE
J 2
(-1875 2375);
DISPLAY 0.872340 (-1875 2375);
DISPLAY INVISIBLE (-1875 2375);
FORCEPROP 1 LAST PATH I38
J 2
(-1548 2500);
DISPLAY 0.872340 (-1548 2500);
PAINT GREEN (-1548 2500);
DISPLAY INVISIBLE (-1548 2500);
FORCEADD TAP..1
R 2
(-1300 2350);
FORCEPROP 3 LASTPIN (-1250 2350) SIG_NAME P5E_CPU0_PE0_TX_DN<8>
J 0
(-1240 2360);
DISPLAY 0.659574 (-1240 2360);
PAINT MONO (-1240 2360);
DISPLAY INVISIBLE (-1240 2360);
FORCEPROP 1 LASTPIN (-1250 2350) BN 8
J 2
(-1238 2358);
DISPLAY 0.680851 (-1238 2358);
PAINT GREEN (-1238 2358);
FORCEPROP 2 LAST CDS_LIB standard
J 0
(-1300 2350);
DISPLAY INVISIBLE (-1300 2350);
FORCEPROP 1 LAST BODY_TYPE PLUMBING
J 2
(-1300 2400);
DISPLAY 0.872340 (-1300 2400);
PAINT GREEN (-1300 2400);
DISPLAY INVISIBLE (-1300 2400);
FORCEPROP 1 LAST HDL_TAP TRUE
J 2
(-1625 2225);
DISPLAY 0.872340 (-1625 2225);
DISPLAY INVISIBLE (-1625 2225);
FORCEPROP 1 LAST PATH I39
J 2
(-1298 2350);
DISPLAY 0.872340 (-1298 2350);
PAINT GREEN (-1298 2350);
DISPLAY INVISIBLE (-1298 2350);
FORCEADD OFFPAGE..1
(-2500 3775);
FORCEPROP 2 LAST $XR0 29 
J 0
(-2751 3775);
DISPLAY 0.638298 (-2751 3775);
PAINT MONO (-2751 3775);
FORCEPROP 2 LAST CDS_LIB standard
J 0
(-2500 3775);
DISPLAY INVISIBLE (-2500 3775);
FORCEPROP 1 LAST OFFPAGE TRUE
J 0
(-2175 3650);
DISPLAY 0.872340 (-2175 3650);
DISPLAY INVISIBLE (-2175 3650);
FORCEPROP 1 LAST COMMENT_BODY TRUE
J 0
(-2375 3675);
DISPLAY 0.872340 (-2375 3675);
PAINT GREEN (-2375 3675);
DISPLAY INVISIBLE (-2375 3675);
FORCEPROP 2 LAST PATH I4
J 0
(-2775 3825);
DISPLAY 1.021277 (-2775 3825);
DISPLAY INVISIBLE (-2775 3825);
FORCEADD TAP..1
R 2
(-1300 2550);
FORCEPROP 3 LASTPIN (-1250 2550) SIG_NAME P5E_CPU0_PE0_TX_DN<9>
J 0
(-1240 2560);
DISPLAY 0.659574 (-1240 2560);
PAINT MONO (-1240 2560);
DISPLAY INVISIBLE (-1240 2560);
FORCEPROP 1 LASTPIN (-1250 2550) BN 9
J 2
(-1238 2558);
DISPLAY 0.680851 (-1238 2558);
PAINT GREEN (-1238 2558);
FORCEPROP 2 LAST CDS_LIB standard
J 0
(-1300 2550);
DISPLAY INVISIBLE (-1300 2550);
FORCEPROP 1 LAST BODY_TYPE PLUMBING
J 2
(-1300 2600);
DISPLAY 0.872340 (-1300 2600);
PAINT GREEN (-1300 2600);
DISPLAY INVISIBLE (-1300 2600);
FORCEPROP 1 LAST HDL_TAP TRUE
J 2
(-1625 2425);
DISPLAY 0.872340 (-1625 2425);
DISPLAY INVISIBLE (-1625 2425);
FORCEPROP 1 LAST PATH I40
J 2
(-1298 2550);
DISPLAY 0.872340 (-1298 2550);
PAINT GREEN (-1298 2550);
DISPLAY INVISIBLE (-1298 2550);
FORCEADD TAP..1
R 2
(-1550 2700);
FORCEPROP 3 LASTPIN (-1500 2700) SIG_NAME P5E_CPU0_PE0_TX_DP<10>
J 0
(-1490 2710);
DISPLAY 0.659574 (-1490 2710);
PAINT MONO (-1490 2710);
DISPLAY INVISIBLE (-1490 2710);
FORCEPROP 1 LASTPIN (-1500 2700) BN 10
J 2
(-1488 2708);
DISPLAY 0.680851 (-1488 2708);
PAINT GREEN (-1488 2708);
FORCEPROP 2 LAST CDS_LIB standard
J 0
(-1550 2700);
DISPLAY INVISIBLE (-1550 2700);
FORCEPROP 1 LAST BODY_TYPE PLUMBING
J 2
(-1550 2750);
DISPLAY 0.872340 (-1550 2750);
PAINT GREEN (-1550 2750);
DISPLAY INVISIBLE (-1550 2750);
FORCEPROP 1 LAST HDL_TAP TRUE
J 2
(-1875 2575);
DISPLAY 0.872340 (-1875 2575);
DISPLAY INVISIBLE (-1875 2575);
FORCEPROP 1 LAST PATH I41
J 2
(-1548 2700);
DISPLAY 0.872340 (-1548 2700);
PAINT GREEN (-1548 2700);
DISPLAY INVISIBLE (-1548 2700);
FORCEADD TAP..1
R 2
(-1550 2900);
FORCEPROP 3 LASTPIN (-1500 2900) SIG_NAME P5E_CPU0_PE0_TX_DP<11>
J 0
(-1490 2910);
DISPLAY 0.659574 (-1490 2910);
PAINT MONO (-1490 2910);
DISPLAY INVISIBLE (-1490 2910);
FORCEPROP 1 LASTPIN (-1500 2900) BN 11
J 2
(-1488 2908);
DISPLAY 0.680851 (-1488 2908);
PAINT GREEN (-1488 2908);
FORCEPROP 2 LAST CDS_LIB standard
J 0
(-1550 2900);
DISPLAY INVISIBLE (-1550 2900);
FORCEPROP 1 LAST BODY_TYPE PLUMBING
J 2
(-1550 2950);
DISPLAY 0.872340 (-1550 2950);
PAINT GREEN (-1550 2950);
DISPLAY INVISIBLE (-1550 2950);
FORCEPROP 1 LAST HDL_TAP TRUE
J 2
(-1875 2775);
DISPLAY 0.872340 (-1875 2775);
DISPLAY INVISIBLE (-1875 2775);
FORCEPROP 1 LAST PATH I42
J 2
(-1548 2900);
DISPLAY 0.872340 (-1548 2900);
PAINT GREEN (-1548 2900);
DISPLAY INVISIBLE (-1548 2900);
FORCEADD TAP..1
R 2
(-1550 3100);
FORCEPROP 3 LASTPIN (-1500 3100) SIG_NAME P5E_CPU0_PE0_TX_DP<12>
J 0
(-1490 3110);
DISPLAY 0.659574 (-1490 3110);
PAINT MONO (-1490 3110);
DISPLAY INVISIBLE (-1490 3110);
FORCEPROP 1 LASTPIN (-1500 3100) BN 12
J 2
(-1488 3108);
DISPLAY 0.680851 (-1488 3108);
PAINT GREEN (-1488 3108);
FORCEPROP 2 LAST CDS_LIB standard
J 0
(-1550 3100);
DISPLAY INVISIBLE (-1550 3100);
FORCEPROP 1 LAST BODY_TYPE PLUMBING
J 2
(-1550 3150);
DISPLAY 0.872340 (-1550 3150);
PAINT GREEN (-1550 3150);
DISPLAY INVISIBLE (-1550 3150);
FORCEPROP 1 LAST HDL_TAP TRUE
J 2
(-1875 2975);
DISPLAY 0.872340 (-1875 2975);
DISPLAY INVISIBLE (-1875 2975);
FORCEPROP 1 LAST PATH I43
J 2
(-1548 3100);
DISPLAY 0.872340 (-1548 3100);
PAINT GREEN (-1548 3100);
DISPLAY INVISIBLE (-1548 3100);
FORCEADD TAP..1
R 2
(-1300 2750);
FORCEPROP 3 LASTPIN (-1250 2750) SIG_NAME P5E_CPU0_PE0_TX_DN<10>
J 0
(-1240 2760);
DISPLAY 0.659574 (-1240 2760);
PAINT MONO (-1240 2760);
DISPLAY INVISIBLE (-1240 2760);
FORCEPROP 1 LASTPIN (-1250 2750) BN 10
J 2
(-1238 2758);
DISPLAY 0.680851 (-1238 2758);
PAINT GREEN (-1238 2758);
FORCEPROP 2 LAST CDS_LIB standard
J 0
(-1300 2750);
DISPLAY INVISIBLE (-1300 2750);
FORCEPROP 1 LAST BODY_TYPE PLUMBING
J 2
(-1300 2800);
DISPLAY 0.872340 (-1300 2800);
PAINT GREEN (-1300 2800);
DISPLAY INVISIBLE (-1300 2800);
FORCEPROP 1 LAST HDL_TAP TRUE
J 2
(-1625 2625);
DISPLAY 0.872340 (-1625 2625);
DISPLAY INVISIBLE (-1625 2625);
FORCEPROP 1 LAST PATH I44
J 2
(-1298 2750);
DISPLAY 0.872340 (-1298 2750);
PAINT GREEN (-1298 2750);
DISPLAY INVISIBLE (-1298 2750);
FORCEADD TAP..1
R 2
(-1300 2950);
FORCEPROP 3 LASTPIN (-1250 2950) SIG_NAME P5E_CPU0_PE0_TX_DN<11>
J 0
(-1240 2960);
DISPLAY 0.659574 (-1240 2960);
PAINT MONO (-1240 2960);
DISPLAY INVISIBLE (-1240 2960);
FORCEPROP 1 LASTPIN (-1250 2950) BN 11
J 2
(-1238 2958);
DISPLAY 0.680851 (-1238 2958);
PAINT GREEN (-1238 2958);
FORCEPROP 2 LAST CDS_LIB standard
J 0
(-1300 2950);
DISPLAY INVISIBLE (-1300 2950);
FORCEPROP 1 LAST BODY_TYPE PLUMBING
J 2
(-1300 3000);
DISPLAY 0.872340 (-1300 3000);
PAINT GREEN (-1300 3000);
DISPLAY INVISIBLE (-1300 3000);
FORCEPROP 1 LAST HDL_TAP TRUE
J 2
(-1625 2825);
DISPLAY 0.872340 (-1625 2825);
DISPLAY INVISIBLE (-1625 2825);
FORCEPROP 1 LAST PATH I45
J 2
(-1298 2950);
DISPLAY 0.872340 (-1298 2950);
PAINT GREEN (-1298 2950);
DISPLAY INVISIBLE (-1298 2950);
FORCEADD TAP..1
R 2
(-1300 3150);
FORCEPROP 3 LASTPIN (-1250 3150) SIG_NAME P5E_CPU0_PE0_TX_DN<12>
J 0
(-1240 3160);
DISPLAY 0.659574 (-1240 3160);
PAINT MONO (-1240 3160);
DISPLAY INVISIBLE (-1240 3160);
FORCEPROP 1 LASTPIN (-1250 3150) BN 12
J 2
(-1238 3158);
DISPLAY 0.680851 (-1238 3158);
PAINT GREEN (-1238 3158);
FORCEPROP 2 LAST CDS_LIB standard
J 0
(-1300 3150);
DISPLAY INVISIBLE (-1300 3150);
FORCEPROP 1 LAST BODY_TYPE PLUMBING
J 2
(-1300 3200);
DISPLAY 0.872340 (-1300 3200);
PAINT GREEN (-1300 3200);
DISPLAY INVISIBLE (-1300 3200);
FORCEPROP 1 LAST HDL_TAP TRUE
J 2
(-1625 3025);
DISPLAY 0.872340 (-1625 3025);
DISPLAY INVISIBLE (-1625 3025);
FORCEPROP 1 LAST PATH I46
J 2
(-1298 3150);
DISPLAY 0.872340 (-1298 3150);
PAINT GREEN (-1298 3150);
DISPLAY INVISIBLE (-1298 3150);
FORCEADD TAP..1
R 2
(-1550 3300);
FORCEPROP 3 LASTPIN (-1500 3300) SIG_NAME P5E_CPU0_PE0_TX_DP<13>
J 0
(-1490 3310);
DISPLAY 0.659574 (-1490 3310);
PAINT MONO (-1490 3310);
DISPLAY INVISIBLE (-1490 3310);
FORCEPROP 1 LASTPIN (-1500 3300) BN 13
J 2
(-1488 3308);
DISPLAY 0.680851 (-1488 3308);
PAINT GREEN (-1488 3308);
FORCEPROP 2 LAST CDS_LIB standard
J 0
(-1550 3300);
DISPLAY INVISIBLE (-1550 3300);
FORCEPROP 1 LAST BODY_TYPE PLUMBING
J 2
(-1550 3350);
DISPLAY 0.872340 (-1550 3350);
PAINT GREEN (-1550 3350);
DISPLAY INVISIBLE (-1550 3350);
FORCEPROP 1 LAST HDL_TAP TRUE
J 2
(-1875 3175);
DISPLAY 0.872340 (-1875 3175);
DISPLAY INVISIBLE (-1875 3175);
FORCEPROP 1 LAST PATH I47
J 2
(-1548 3300);
DISPLAY 0.872340 (-1548 3300);
PAINT GREEN (-1548 3300);
DISPLAY INVISIBLE (-1548 3300);
FORCEADD TAP..1
R 2
(-1550 3500);
FORCEPROP 3 LASTPIN (-1500 3500) SIG_NAME P5E_CPU0_PE0_TX_DP<14>
J 0
(-1490 3510);
DISPLAY 0.659574 (-1490 3510);
PAINT MONO (-1490 3510);
DISPLAY INVISIBLE (-1490 3510);
FORCEPROP 1 LASTPIN (-1500 3500) BN 14
J 2
(-1488 3508);
DISPLAY 0.680851 (-1488 3508);
PAINT GREEN (-1488 3508);
FORCEPROP 2 LAST CDS_LIB standard
J 0
(-1550 3500);
DISPLAY INVISIBLE (-1550 3500);
FORCEPROP 1 LAST BODY_TYPE PLUMBING
J 2
(-1550 3550);
DISPLAY 0.872340 (-1550 3550);
PAINT GREEN (-1550 3550);
DISPLAY INVISIBLE (-1550 3550);
FORCEPROP 1 LAST HDL_TAP TRUE
J 2
(-1875 3375);
DISPLAY 0.872340 (-1875 3375);
DISPLAY INVISIBLE (-1875 3375);
FORCEPROP 1 LAST PATH I48
J 2
(-1548 3500);
DISPLAY 0.872340 (-1548 3500);
PAINT GREEN (-1548 3500);
DISPLAY INVISIBLE (-1548 3500);
FORCEADD TAP..1
R 2
(-1550 3700);
FORCEPROP 3 LASTPIN (-1500 3700) SIG_NAME P5E_CPU0_PE0_TX_DP<15>
J 0
(-1490 3710);
DISPLAY 0.659574 (-1490 3710);
PAINT MONO (-1490 3710);
DISPLAY INVISIBLE (-1490 3710);
FORCEPROP 1 LASTPIN (-1500 3700) BN 15
J 2
(-1488 3708);
DISPLAY 0.680851 (-1488 3708);
PAINT GREEN (-1488 3708);
FORCEPROP 2 LAST CDS_LIB standard
J 0
(-1550 3700);
DISPLAY INVISIBLE (-1550 3700);
FORCEPROP 1 LAST BODY_TYPE PLUMBING
J 2
(-1550 3750);
DISPLAY 0.872340 (-1550 3750);
PAINT GREEN (-1550 3750);
DISPLAY INVISIBLE (-1550 3750);
FORCEPROP 1 LAST HDL_TAP TRUE
J 2
(-1875 3575);
DISPLAY 0.872340 (-1875 3575);
DISPLAY INVISIBLE (-1875 3575);
FORCEPROP 1 LAST PATH I49
J 2
(-1548 3700);
DISPLAY 0.872340 (-1548 3700);
PAINT GREEN (-1548 3700);
DISPLAY INVISIBLE (-1548 3700);
FORCEADD TAP..1
R 2
(-1550 325);
FORCEPROP 3 LASTPIN (-1500 325) SIG_NAME P5E_CPU0_PE0_TX_DP<0>
J 0
(-1490 335);
DISPLAY 0.659574 (-1490 335);
PAINT MONO (-1490 335);
DISPLAY INVISIBLE (-1490 335);
FORCEPROP 1 LASTPIN (-1500 325) BN 0
J 2
(-1488 333);
DISPLAY 0.680851 (-1488 333);
PAINT GREEN (-1488 333);
FORCEPROP 2 LAST CDS_LIB standard
J 0
(-1550 325);
DISPLAY INVISIBLE (-1550 325);
FORCEPROP 1 LAST BODY_TYPE PLUMBING
J 2
(-1550 375);
DISPLAY 0.872340 (-1550 375);
PAINT GREEN (-1550 375);
DISPLAY INVISIBLE (-1550 375);
FORCEPROP 1 LAST HDL_TAP TRUE
J 2
(-1875 200);
DISPLAY 0.872340 (-1875 200);
DISPLAY INVISIBLE (-1875 200);
FORCEPROP 1 LAST PATH I5
J 2
(-1548 325);
DISPLAY 0.872340 (-1548 325);
PAINT GREEN (-1548 325);
DISPLAY INVISIBLE (-1548 325);
FORCEADD TAP..1
R 2
(-1300 3350);
FORCEPROP 3 LASTPIN (-1250 3350) SIG_NAME P5E_CPU0_PE0_TX_DN<13>
J 0
(-1240 3360);
DISPLAY 0.659574 (-1240 3360);
PAINT MONO (-1240 3360);
DISPLAY INVISIBLE (-1240 3360);
FORCEPROP 1 LASTPIN (-1250 3350) BN 13
J 2
(-1238 3358);
DISPLAY 0.680851 (-1238 3358);
PAINT GREEN (-1238 3358);
FORCEPROP 2 LAST CDS_LIB standard
J 0
(-1300 3350);
DISPLAY INVISIBLE (-1300 3350);
FORCEPROP 1 LAST BODY_TYPE PLUMBING
J 2
(-1300 3400);
DISPLAY 0.872340 (-1300 3400);
PAINT GREEN (-1300 3400);
DISPLAY INVISIBLE (-1300 3400);
FORCEPROP 1 LAST HDL_TAP TRUE
J 2
(-1625 3225);
DISPLAY 0.872340 (-1625 3225);
DISPLAY INVISIBLE (-1625 3225);
FORCEPROP 1 LAST PATH I50
J 2
(-1298 3350);
DISPLAY 0.872340 (-1298 3350);
PAINT GREEN (-1298 3350);
DISPLAY INVISIBLE (-1298 3350);
FORCEADD TAP..1
R 2
(-1300 3550);
FORCEPROP 3 LASTPIN (-1250 3550) SIG_NAME P5E_CPU0_PE0_TX_DN<14>
J 0
(-1240 3560);
DISPLAY 0.659574 (-1240 3560);
PAINT MONO (-1240 3560);
DISPLAY INVISIBLE (-1240 3560);
FORCEPROP 1 LASTPIN (-1250 3550) BN 14
J 2
(-1238 3558);
DISPLAY 0.680851 (-1238 3558);
PAINT GREEN (-1238 3558);
FORCEPROP 2 LAST CDS_LIB standard
J 0
(-1300 3550);
DISPLAY INVISIBLE (-1300 3550);
FORCEPROP 1 LAST BODY_TYPE PLUMBING
J 2
(-1300 3600);
DISPLAY 0.872340 (-1300 3600);
PAINT GREEN (-1300 3600);
DISPLAY INVISIBLE (-1300 3600);
FORCEPROP 1 LAST HDL_TAP TRUE
J 2
(-1625 3425);
DISPLAY 0.872340 (-1625 3425);
DISPLAY INVISIBLE (-1625 3425);
FORCEPROP 1 LAST PATH I51
J 2
(-1298 3550);
DISPLAY 0.872340 (-1298 3550);
PAINT GREEN (-1298 3550);
DISPLAY INVISIBLE (-1298 3550);
FORCEADD TAP..1
R 2
(-1300 3750);
FORCEPROP 3 LASTPIN (-1250 3750) SIG_NAME P5E_CPU0_PE0_TX_DN<15>
J 0
(-1240 3760);
DISPLAY 0.659574 (-1240 3760);
PAINT MONO (-1240 3760);
DISPLAY INVISIBLE (-1240 3760);
FORCEPROP 1 LASTPIN (-1250 3750) BN 15
J 2
(-1238 3758);
DISPLAY 0.680851 (-1238 3758);
PAINT GREEN (-1238 3758);
FORCEPROP 2 LAST CDS_LIB standard
J 0
(-1300 3750);
DISPLAY INVISIBLE (-1300 3750);
FORCEPROP 1 LAST BODY_TYPE PLUMBING
J 2
(-1300 3800);
DISPLAY 0.872340 (-1300 3800);
PAINT GREEN (-1300 3800);
DISPLAY INVISIBLE (-1300 3800);
FORCEPROP 1 LAST HDL_TAP TRUE
J 2
(-1625 3625);
DISPLAY 0.872340 (-1625 3625);
DISPLAY INVISIBLE (-1625 3625);
FORCEPROP 1 LAST PATH I52
J 2
(-1298 3750);
DISPLAY 0.872340 (-1298 3750);
PAINT GREEN (-1298 3750);
DISPLAY INVISIBLE (-1298 3750);
FORCEADD Q_CAP_DIFFBUS..2
R 2
(-575 2350);
FORCEPROP 1 LAST PART_NUMBER SP_CH4221MEE01
J 2
(-691 2438);
DISPLAY 0.574468 (-691 2438);
PAINT GREEN (-691 2438);
DISPLAY INVISIBLE (-691 2438);
FORCEPROP 2 LAST VALUE DIFF BUS_0.22UF
J 2
(-725 2350);
DISPLAY 0.553191 (-725 2350);
FORCEPROP 1 LAST $LOCATION C916
J 2
(-341 2367);
DISPLAY 0.723404 (-341 2367);
PAINT GREEN (-341 2367);
FORCEPROP 2 LASTPIN (-500 2350) $PN 1
J 0
(-490 2360);
DISPLAY 0.808511 (-490 2360);
FORCEPROP 2 LASTPIN (-650 2350) $PN 2
J 2
(-660 2360);
DISPLAY 0.808511 (-660 2360);
FORCEPROP 2 LAST TOLERANCE 20%
J 2
(-650 2400);
DISPLAY 0.553191 (-650 2400);
DISPLAY INVISIBLE (-650 2400);
FORCEPROP 2 LAST PACK_TYPE C0201
J 2
(-750 2400);
DISPLAY 0.553191 (-750 2400);
DISPLAY INVISIBLE (-750 2400);
FORCEPROP 1 LAST MATERIAL X6S
J 2
(-566 2429);
DISPLAY 0.574468 (-566 2429);
PAINT GREEN (-566 2429);
DISPLAY INVISIBLE (-566 2429);
FORCEPROP 2 LAST VOLTAGE 6.3V
J 2
(-925 2400);
DISPLAY 0.553191 (-925 2400);
DISPLAY INVISIBLE (-925 2400);
FORCEPROP 1 LAST PIN_NAMES_ROTATE TRUE
J 2
(-575 2350);
DISPLAY 0.489362 (-575 2350);
PAINT GREEN (-575 2350);
DISPLAY INVISIBLE (-575 2350);
FORCEPROP 2 LAST CDS_LIB pure_quanta
J 2
(-575 2350);
DISPLAY INVISIBLE (-575 2350);
FORCEPROP 1 LAST CDS_LMAN_SYM_OUTLINE -25,50,25,-50
J 2
(-575 2350);
DISPLAY 0.468085 (-575 2350);
PAINT GREEN (-575 2350);
DISPLAY INVISIBLE (-575 2350);
FORCEPROP 1 LAST PATH I53
J 2
(-575 2350);
DISPLAY 0.723404 (-575 2350);
DISPLAY INVISIBLE (-575 2350);
FORCEPROP 1 LAST $LOCATION C916
J 0
(-325 2425);
DISPLAY 1.021277 (-325 2425);
DISPLAY INVISIBLE (-325 2425);
FORCEPROP 2 LAST CDS_LOCATION C916
J 0
(-325 2425);
DISPLAY 1.021277 (-325 2425);
DISPLAY INVISIBLE (-325 2425);
FORCEPROP 2 LAST $SEC 1
J 2
(-400 2425);
DISPLAY 0.680851 (-400 2425);
PAINT MONO (-400 2425);
DISPLAY INVISIBLE (-400 2425);
FORCEPROP 2 LAST CDS_SEC 1
J 2
(-400 2425);
DISPLAY 0.680851 (-400 2425);
DISPLAY INVISIBLE (-400 2425);
FORCEADD Q_CAP_DIFFBUS..2
R 2
(-575 2300);
FORCEPROP 1 LAST PART_NUMBER SP_CH4221MEE01
J 2
(-691 2388);
DISPLAY 0.574468 (-691 2388);
PAINT GREEN (-691 2388);
DISPLAY INVISIBLE (-691 2388);
FORCEPROP 2 LAST VALUE DIFF BUS_0.22UF
J 2
(-725 2300);
DISPLAY 0.553191 (-725 2300);
FORCEPROP 1 LAST $LOCATION C917
J 2
(-341 2317);
DISPLAY 0.723404 (-341 2317);
PAINT GREEN (-341 2317);
FORCEPROP 2 LASTPIN (-500 2300) $PN 1
J 0
(-490 2310);
DISPLAY 0.808511 (-490 2310);
FORCEPROP 2 LASTPIN (-650 2300) $PN 2
J 2
(-660 2310);
DISPLAY 0.808511 (-660 2310);
FORCEPROP 2 LAST TOLERANCE 20%
J 2
(-650 2350);
DISPLAY 0.553191 (-650 2350);
DISPLAY INVISIBLE (-650 2350);
FORCEPROP 2 LAST PACK_TYPE C0201
J 2
(-750 2350);
DISPLAY 0.553191 (-750 2350);
DISPLAY INVISIBLE (-750 2350);
FORCEPROP 1 LAST MATERIAL X6S
J 2
(-566 2379);
DISPLAY 0.574468 (-566 2379);
PAINT GREEN (-566 2379);
DISPLAY INVISIBLE (-566 2379);
FORCEPROP 2 LAST VOLTAGE 6.3V
J 2
(-925 2350);
DISPLAY 0.553191 (-925 2350);
DISPLAY INVISIBLE (-925 2350);
FORCEPROP 1 LAST PIN_NAMES_ROTATE TRUE
J 2
(-575 2300);
DISPLAY 0.489362 (-575 2300);
PAINT GREEN (-575 2300);
DISPLAY INVISIBLE (-575 2300);
FORCEPROP 2 LAST CDS_LIB pure_quanta
J 2
(-575 2300);
DISPLAY INVISIBLE (-575 2300);
FORCEPROP 1 LAST CDS_LMAN_SYM_OUTLINE -25,50,25,-50
J 2
(-575 2300);
DISPLAY 0.468085 (-575 2300);
PAINT GREEN (-575 2300);
DISPLAY INVISIBLE (-575 2300);
FORCEPROP 1 LAST PATH I54
J 2
(-575 2300);
DISPLAY 0.723404 (-575 2300);
DISPLAY INVISIBLE (-575 2300);
FORCEPROP 1 LAST $LOCATION C917
J 0
(-325 2375);
DISPLAY 1.021277 (-325 2375);
DISPLAY INVISIBLE (-325 2375);
FORCEPROP 2 LAST CDS_LOCATION C917
J 0
(-325 2375);
DISPLAY 1.021277 (-325 2375);
DISPLAY INVISIBLE (-325 2375);
FORCEPROP 2 LAST $SEC 1
J 2
(-400 2375);
DISPLAY 0.680851 (-400 2375);
PAINT MONO (-400 2375);
DISPLAY INVISIBLE (-400 2375);
FORCEPROP 2 LAST CDS_SEC 1
J 2
(-400 2375);
DISPLAY 0.680851 (-400 2375);
DISPLAY INVISIBLE (-400 2375);
FORCEADD Q_CAP_DIFFBUS..2
R 2
(-575 2500);
FORCEPROP 1 LAST PART_NUMBER SP_CH4221MEE01
J 2
(-691 2588);
DISPLAY 0.574468 (-691 2588);
PAINT GREEN (-691 2588);
DISPLAY INVISIBLE (-691 2588);
FORCEPROP 2 LAST VALUE DIFF BUS_0.22UF
J 2
(-725 2500);
DISPLAY 0.553191 (-725 2500);
FORCEPROP 1 LAST $LOCATION C915
J 2
(-341 2517);
DISPLAY 0.723404 (-341 2517);
PAINT GREEN (-341 2517);
FORCEPROP 2 LASTPIN (-500 2500) $PN 1
J 0
(-490 2510);
DISPLAY 0.808511 (-490 2510);
FORCEPROP 2 LASTPIN (-650 2500) $PN 2
J 2
(-660 2510);
DISPLAY 0.808511 (-660 2510);
FORCEPROP 2 LAST TOLERANCE 20%
J 2
(-650 2550);
DISPLAY 0.553191 (-650 2550);
DISPLAY INVISIBLE (-650 2550);
FORCEPROP 2 LAST PACK_TYPE C0201
J 2
(-750 2550);
DISPLAY 0.553191 (-750 2550);
DISPLAY INVISIBLE (-750 2550);
FORCEPROP 1 LAST MATERIAL X6S
J 2
(-566 2579);
DISPLAY 0.574468 (-566 2579);
PAINT GREEN (-566 2579);
DISPLAY INVISIBLE (-566 2579);
FORCEPROP 2 LAST VOLTAGE 6.3V
J 2
(-925 2550);
DISPLAY 0.553191 (-925 2550);
DISPLAY INVISIBLE (-925 2550);
FORCEPROP 1 LAST PIN_NAMES_ROTATE TRUE
J 2
(-575 2500);
DISPLAY 0.489362 (-575 2500);
PAINT GREEN (-575 2500);
DISPLAY INVISIBLE (-575 2500);
FORCEPROP 2 LAST CDS_LIB pure_quanta
J 2
(-575 2500);
DISPLAY INVISIBLE (-575 2500);
FORCEPROP 1 LAST CDS_LMAN_SYM_OUTLINE -25,50,25,-50
J 2
(-575 2500);
DISPLAY 0.468085 (-575 2500);
PAINT GREEN (-575 2500);
DISPLAY INVISIBLE (-575 2500);
FORCEPROP 1 LAST PATH I55
J 2
(-575 2500);
DISPLAY 0.723404 (-575 2500);
DISPLAY INVISIBLE (-575 2500);
FORCEPROP 1 LAST $LOCATION C915
J 0
(-325 2575);
DISPLAY 1.021277 (-325 2575);
DISPLAY INVISIBLE (-325 2575);
FORCEPROP 2 LAST CDS_LOCATION C915
J 0
(-325 2575);
DISPLAY 1.021277 (-325 2575);
DISPLAY INVISIBLE (-325 2575);
FORCEPROP 2 LAST $SEC 1
J 2
(-400 2575);
DISPLAY 0.680851 (-400 2575);
PAINT MONO (-400 2575);
DISPLAY INVISIBLE (-400 2575);
FORCEPROP 2 LAST CDS_SEC 1
J 2
(-400 2575);
DISPLAY 0.680851 (-400 2575);
DISPLAY INVISIBLE (-400 2575);
FORCEADD Q_CAP_DIFFBUS..2
R 2
(-575 2550);
FORCEPROP 1 LAST PART_NUMBER SP_CH4221MEE01
J 2
(-691 2638);
DISPLAY 0.574468 (-691 2638);
PAINT GREEN (-691 2638);
DISPLAY INVISIBLE (-691 2638);
FORCEPROP 2 LAST VALUE DIFF BUS_0.22UF
J 2
(-725 2550);
DISPLAY 0.553191 (-725 2550);
FORCEPROP 1 LAST $LOCATION C914
J 2
(-341 2567);
DISPLAY 0.723404 (-341 2567);
PAINT GREEN (-341 2567);
FORCEPROP 2 LASTPIN (-500 2550) $PN 1
J 0
(-490 2560);
DISPLAY 0.808511 (-490 2560);
FORCEPROP 2 LASTPIN (-650 2550) $PN 2
J 2
(-660 2560);
DISPLAY 0.808511 (-660 2560);
FORCEPROP 2 LAST TOLERANCE 20%
J 2
(-650 2600);
DISPLAY 0.553191 (-650 2600);
DISPLAY INVISIBLE (-650 2600);
FORCEPROP 2 LAST PACK_TYPE C0201
J 2
(-750 2600);
DISPLAY 0.553191 (-750 2600);
DISPLAY INVISIBLE (-750 2600);
FORCEPROP 1 LAST MATERIAL X6S
J 2
(-566 2629);
DISPLAY 0.574468 (-566 2629);
PAINT GREEN (-566 2629);
DISPLAY INVISIBLE (-566 2629);
FORCEPROP 2 LAST VOLTAGE 6.3V
J 2
(-925 2600);
DISPLAY 0.553191 (-925 2600);
DISPLAY INVISIBLE (-925 2600);
FORCEPROP 1 LAST PIN_NAMES_ROTATE TRUE
J 2
(-575 2550);
DISPLAY 0.489362 (-575 2550);
PAINT GREEN (-575 2550);
DISPLAY INVISIBLE (-575 2550);
FORCEPROP 1 LAST CDS_LMAN_SYM_OUTLINE -25,50,25,-50
J 2
(-575 2550);
DISPLAY 0.468085 (-575 2550);
PAINT GREEN (-575 2550);
DISPLAY INVISIBLE (-575 2550);
FORCEPROP 2 LAST CDS_LIB pure_quanta
J 2
(-575 2550);
DISPLAY INVISIBLE (-575 2550);
FORCEPROP 1 LAST PATH I56
J 2
(-575 2550);
DISPLAY 0.723404 (-575 2550);
DISPLAY INVISIBLE (-575 2550);
FORCEPROP 1 LAST $LOCATION C914
J 0
(-325 2625);
DISPLAY 1.021277 (-325 2625);
DISPLAY INVISIBLE (-325 2625);
FORCEPROP 2 LAST CDS_LOCATION C914
J 0
(-325 2625);
DISPLAY 1.021277 (-325 2625);
DISPLAY INVISIBLE (-325 2625);
FORCEPROP 2 LAST $SEC 1
J 2
(-400 2625);
DISPLAY 0.680851 (-400 2625);
PAINT MONO (-400 2625);
DISPLAY INVISIBLE (-400 2625);
FORCEPROP 2 LAST CDS_SEC 1
J 2
(-400 2625);
DISPLAY 0.680851 (-400 2625);
DISPLAY INVISIBLE (-400 2625);
FORCEADD Q_CAP_DIFFBUS..2
R 2
(-575 2700);
FORCEPROP 1 LAST PART_NUMBER SP_CH4221MEE01
J 2
(-691 2788);
DISPLAY 0.574468 (-691 2788);
PAINT GREEN (-691 2788);
DISPLAY INVISIBLE (-691 2788);
FORCEPROP 2 LAST VALUE DIFF BUS_0.22UF
J 2
(-725 2700);
DISPLAY 0.553191 (-725 2700);
FORCEPROP 1 LAST $LOCATION C913
J 2
(-341 2717);
DISPLAY 0.723404 (-341 2717);
PAINT GREEN (-341 2717);
FORCEPROP 2 LASTPIN (-500 2700) $PN 1
J 0
(-490 2710);
DISPLAY 0.808511 (-490 2710);
FORCEPROP 2 LASTPIN (-650 2700) $PN 2
J 2
(-660 2710);
DISPLAY 0.808511 (-660 2710);
FORCEPROP 2 LAST TOLERANCE 20%
J 2
(-650 2750);
DISPLAY 0.553191 (-650 2750);
DISPLAY INVISIBLE (-650 2750);
FORCEPROP 2 LAST PACK_TYPE C0201
J 2
(-750 2750);
DISPLAY 0.553191 (-750 2750);
DISPLAY INVISIBLE (-750 2750);
FORCEPROP 1 LAST MATERIAL X6S
J 2
(-566 2779);
DISPLAY 0.574468 (-566 2779);
PAINT GREEN (-566 2779);
DISPLAY INVISIBLE (-566 2779);
FORCEPROP 2 LAST VOLTAGE 6.3V
J 2
(-925 2750);
DISPLAY 0.553191 (-925 2750);
DISPLAY INVISIBLE (-925 2750);
FORCEPROP 1 LAST PIN_NAMES_ROTATE TRUE
J 2
(-575 2700);
DISPLAY 0.489362 (-575 2700);
PAINT GREEN (-575 2700);
DISPLAY INVISIBLE (-575 2700);
FORCEPROP 2 LAST CDS_LIB pure_quanta
J 2
(-575 2700);
DISPLAY INVISIBLE (-575 2700);
FORCEPROP 1 LAST CDS_LMAN_SYM_OUTLINE -25,50,25,-50
J 2
(-575 2700);
DISPLAY 0.468085 (-575 2700);
PAINT GREEN (-575 2700);
DISPLAY INVISIBLE (-575 2700);
FORCEPROP 1 LAST PATH I57
J 2
(-575 2700);
DISPLAY 0.723404 (-575 2700);
DISPLAY INVISIBLE (-575 2700);
FORCEPROP 1 LAST $LOCATION C913
J 0
(-325 2775);
DISPLAY 1.021277 (-325 2775);
DISPLAY INVISIBLE (-325 2775);
FORCEPROP 2 LAST CDS_LOCATION C913
J 0
(-325 2775);
DISPLAY 1.021277 (-325 2775);
DISPLAY INVISIBLE (-325 2775);
FORCEPROP 2 LAST $SEC 1
J 2
(-400 2775);
DISPLAY 0.680851 (-400 2775);
PAINT MONO (-400 2775);
DISPLAY INVISIBLE (-400 2775);
FORCEPROP 2 LAST CDS_SEC 1
J 2
(-400 2775);
DISPLAY 0.680851 (-400 2775);
DISPLAY INVISIBLE (-400 2775);
FORCEADD Q_CAP_DIFFBUS..2
R 2
(-575 2750);
FORCEPROP 1 LAST PART_NUMBER SP_CH4221MEE01
J 2
(-691 2838);
DISPLAY 0.574468 (-691 2838);
PAINT GREEN (-691 2838);
DISPLAY INVISIBLE (-691 2838);
FORCEPROP 2 LAST VALUE DIFF BUS_0.22UF
J 2
(-725 2750);
DISPLAY 0.553191 (-725 2750);
FORCEPROP 1 LAST $LOCATION C912
J 2
(-341 2767);
DISPLAY 0.723404 (-341 2767);
PAINT GREEN (-341 2767);
FORCEPROP 2 LASTPIN (-500 2750) $PN 1
J 0
(-490 2760);
DISPLAY 0.808511 (-490 2760);
FORCEPROP 2 LASTPIN (-650 2750) $PN 2
J 2
(-660 2760);
DISPLAY 0.808511 (-660 2760);
FORCEPROP 2 LAST TOLERANCE 20%
J 2
(-650 2800);
DISPLAY 0.553191 (-650 2800);
DISPLAY INVISIBLE (-650 2800);
FORCEPROP 2 LAST PACK_TYPE C0201
J 2
(-750 2800);
DISPLAY 0.553191 (-750 2800);
DISPLAY INVISIBLE (-750 2800);
FORCEPROP 1 LAST MATERIAL X6S
J 2
(-566 2829);
DISPLAY 0.574468 (-566 2829);
PAINT GREEN (-566 2829);
DISPLAY INVISIBLE (-566 2829);
FORCEPROP 2 LAST VOLTAGE 6.3V
J 2
(-925 2800);
DISPLAY 0.553191 (-925 2800);
DISPLAY INVISIBLE (-925 2800);
FORCEPROP 1 LAST PIN_NAMES_ROTATE TRUE
J 2
(-575 2750);
DISPLAY 0.489362 (-575 2750);
PAINT GREEN (-575 2750);
DISPLAY INVISIBLE (-575 2750);
FORCEPROP 2 LAST CDS_LIB pure_quanta
J 2
(-575 2750);
DISPLAY INVISIBLE (-575 2750);
FORCEPROP 1 LAST CDS_LMAN_SYM_OUTLINE -25,50,25,-50
J 2
(-575 2750);
DISPLAY 0.468085 (-575 2750);
PAINT GREEN (-575 2750);
DISPLAY INVISIBLE (-575 2750);
FORCEPROP 1 LAST PATH I58
J 2
(-575 2750);
DISPLAY 0.723404 (-575 2750);
DISPLAY INVISIBLE (-575 2750);
FORCEPROP 1 LAST $LOCATION C912
J 0
(-325 2825);
DISPLAY 1.021277 (-325 2825);
DISPLAY INVISIBLE (-325 2825);
FORCEPROP 2 LAST CDS_LOCATION C912
J 0
(-325 2825);
DISPLAY 1.021277 (-325 2825);
DISPLAY INVISIBLE (-325 2825);
FORCEPROP 2 LAST $SEC 1
J 2
(-400 2825);
DISPLAY 0.680851 (-400 2825);
PAINT MONO (-400 2825);
DISPLAY INVISIBLE (-400 2825);
FORCEPROP 2 LAST CDS_SEC 1
J 2
(-400 2825);
DISPLAY 0.680851 (-400 2825);
DISPLAY INVISIBLE (-400 2825);
FORCEADD Q_CAP_DIFFBUS..2
R 2
(-575 2900);
FORCEPROP 1 LAST PART_NUMBER SP_CH4221MEE01
J 2
(-691 2988);
DISPLAY 0.574468 (-691 2988);
PAINT GREEN (-691 2988);
DISPLAY INVISIBLE (-691 2988);
FORCEPROP 2 LAST VALUE DIFF BUS_0.22UF
J 2
(-725 2900);
DISPLAY 0.553191 (-725 2900);
FORCEPROP 1 LAST $LOCATION C911
J 2
(-341 2917);
DISPLAY 0.723404 (-341 2917);
PAINT GREEN (-341 2917);
FORCEPROP 2 LASTPIN (-500 2900) $PN 1
J 0
(-490 2910);
DISPLAY 0.808511 (-490 2910);
FORCEPROP 2 LASTPIN (-650 2900) $PN 2
J 2
(-660 2910);
DISPLAY 0.808511 (-660 2910);
FORCEPROP 2 LAST TOLERANCE 20%
J 2
(-650 2950);
DISPLAY 0.553191 (-650 2950);
DISPLAY INVISIBLE (-650 2950);
FORCEPROP 2 LAST PACK_TYPE C0201
J 2
(-750 2950);
DISPLAY 0.553191 (-750 2950);
DISPLAY INVISIBLE (-750 2950);
FORCEPROP 1 LAST MATERIAL X6S
J 2
(-566 2979);
DISPLAY 0.574468 (-566 2979);
PAINT GREEN (-566 2979);
DISPLAY INVISIBLE (-566 2979);
FORCEPROP 2 LAST VOLTAGE 6.3V
J 2
(-925 2950);
DISPLAY 0.553191 (-925 2950);
DISPLAY INVISIBLE (-925 2950);
FORCEPROP 1 LAST PIN_NAMES_ROTATE TRUE
J 2
(-575 2900);
DISPLAY 0.489362 (-575 2900);
PAINT GREEN (-575 2900);
DISPLAY INVISIBLE (-575 2900);
FORCEPROP 1 LAST CDS_LMAN_SYM_OUTLINE -25,50,25,-50
J 2
(-575 2900);
DISPLAY 0.468085 (-575 2900);
PAINT GREEN (-575 2900);
DISPLAY INVISIBLE (-575 2900);
FORCEPROP 2 LAST CDS_LIB pure_quanta
J 2
(-575 2900);
DISPLAY INVISIBLE (-575 2900);
FORCEPROP 1 LAST PATH I59
J 2
(-575 2900);
DISPLAY 0.723404 (-575 2900);
DISPLAY INVISIBLE (-575 2900);
FORCEPROP 1 LAST $LOCATION C911
J 0
(-325 2975);
DISPLAY 1.021277 (-325 2975);
DISPLAY INVISIBLE (-325 2975);
FORCEPROP 2 LAST CDS_LOCATION C911
J 0
(-325 2975);
DISPLAY 1.021277 (-325 2975);
DISPLAY INVISIBLE (-325 2975);
FORCEPROP 2 LAST $SEC 1
J 2
(-400 2975);
DISPLAY 0.680851 (-400 2975);
PAINT MONO (-400 2975);
DISPLAY INVISIBLE (-400 2975);
FORCEPROP 2 LAST CDS_SEC 1
J 2
(-400 2975);
DISPLAY 0.680851 (-400 2975);
DISPLAY INVISIBLE (-400 2975);
FORCEADD TAP..1
R 2
(-1550 525);
FORCEPROP 3 LASTPIN (-1500 525) SIG_NAME P5E_CPU0_PE0_TX_DP<1>
J 0
(-1490 535);
DISPLAY 0.659574 (-1490 535);
PAINT MONO (-1490 535);
DISPLAY INVISIBLE (-1490 535);
FORCEPROP 1 LASTPIN (-1500 525) BN 1
J 2
(-1488 533);
DISPLAY 0.680851 (-1488 533);
PAINT GREEN (-1488 533);
FORCEPROP 2 LAST CDS_LIB standard
J 0
(-1550 525);
DISPLAY INVISIBLE (-1550 525);
FORCEPROP 1 LAST BODY_TYPE PLUMBING
J 2
(-1550 575);
DISPLAY 0.872340 (-1550 575);
PAINT GREEN (-1550 575);
DISPLAY INVISIBLE (-1550 575);
FORCEPROP 1 LAST HDL_TAP TRUE
J 2
(-1875 400);
DISPLAY 0.872340 (-1875 400);
DISPLAY INVISIBLE (-1875 400);
FORCEPROP 1 LAST PATH I6
J 2
(-1548 525);
DISPLAY 0.872340 (-1548 525);
PAINT GREEN (-1548 525);
DISPLAY INVISIBLE (-1548 525);
FORCEADD Q_CAP_DIFFBUS..2
R 2
(-575 2950);
FORCEPROP 1 LAST PART_NUMBER SP_CH4221MEE01
J 2
(-691 3038);
DISPLAY 0.574468 (-691 3038);
PAINT GREEN (-691 3038);
DISPLAY INVISIBLE (-691 3038);
FORCEPROP 2 LAST VALUE DIFF BUS_0.22UF
J 2
(-725 2950);
DISPLAY 0.553191 (-725 2950);
FORCEPROP 1 LAST $LOCATION C910
J 2
(-341 2967);
DISPLAY 0.723404 (-341 2967);
PAINT GREEN (-341 2967);
FORCEPROP 2 LASTPIN (-500 2950) $PN 1
J 0
(-490 2960);
DISPLAY 0.808511 (-490 2960);
FORCEPROP 2 LASTPIN (-650 2950) $PN 2
J 2
(-660 2960);
DISPLAY 0.808511 (-660 2960);
FORCEPROP 2 LAST TOLERANCE 20%
J 2
(-650 3000);
DISPLAY 0.553191 (-650 3000);
DISPLAY INVISIBLE (-650 3000);
FORCEPROP 2 LAST PACK_TYPE C0201
J 2
(-750 3000);
DISPLAY 0.553191 (-750 3000);
DISPLAY INVISIBLE (-750 3000);
FORCEPROP 1 LAST MATERIAL X6S
J 2
(-566 3029);
DISPLAY 0.574468 (-566 3029);
PAINT GREEN (-566 3029);
DISPLAY INVISIBLE (-566 3029);
FORCEPROP 2 LAST VOLTAGE 6.3V
J 2
(-925 3000);
DISPLAY 0.553191 (-925 3000);
DISPLAY INVISIBLE (-925 3000);
FORCEPROP 1 LAST PIN_NAMES_ROTATE TRUE
J 2
(-575 2950);
DISPLAY 0.489362 (-575 2950);
PAINT GREEN (-575 2950);
DISPLAY INVISIBLE (-575 2950);
FORCEPROP 1 LAST CDS_LMAN_SYM_OUTLINE -25,50,25,-50
J 2
(-575 2950);
DISPLAY 0.468085 (-575 2950);
PAINT GREEN (-575 2950);
DISPLAY INVISIBLE (-575 2950);
FORCEPROP 2 LAST CDS_LIB pure_quanta
J 2
(-575 2950);
DISPLAY INVISIBLE (-575 2950);
FORCEPROP 1 LAST PATH I60
J 2
(-575 2950);
DISPLAY 0.723404 (-575 2950);
DISPLAY INVISIBLE (-575 2950);
FORCEPROP 1 LAST $LOCATION C910
J 0
(-325 3025);
DISPLAY 1.021277 (-325 3025);
DISPLAY INVISIBLE (-325 3025);
FORCEPROP 2 LAST CDS_LOCATION C910
J 0
(-325 3025);
DISPLAY 1.021277 (-325 3025);
DISPLAY INVISIBLE (-325 3025);
FORCEPROP 2 LAST $SEC 1
J 2
(-400 3025);
DISPLAY 0.680851 (-400 3025);
PAINT MONO (-400 3025);
DISPLAY INVISIBLE (-400 3025);
FORCEPROP 2 LAST CDS_SEC 1
J 2
(-400 3025);
DISPLAY 0.680851 (-400 3025);
DISPLAY INVISIBLE (-400 3025);
FORCEADD Q_CAP_DIFFBUS..2
R 2
(-575 3100);
FORCEPROP 1 LAST PART_NUMBER SP_CH4221MEE01
J 2
(-691 3188);
DISPLAY 0.574468 (-691 3188);
PAINT GREEN (-691 3188);
DISPLAY INVISIBLE (-691 3188);
FORCEPROP 2 LAST VALUE DIFF BUS_0.22UF
J 2
(-725 3100);
DISPLAY 0.553191 (-725 3100);
FORCEPROP 1 LAST $LOCATION C909
J 2
(-341 3117);
DISPLAY 0.723404 (-341 3117);
PAINT GREEN (-341 3117);
FORCEPROP 2 LASTPIN (-500 3100) $PN 1
J 0
(-490 3110);
DISPLAY 0.808511 (-490 3110);
FORCEPROP 2 LASTPIN (-650 3100) $PN 2
J 2
(-660 3110);
DISPLAY 0.808511 (-660 3110);
FORCEPROP 2 LAST TOLERANCE 20%
J 2
(-650 3150);
DISPLAY 0.553191 (-650 3150);
DISPLAY INVISIBLE (-650 3150);
FORCEPROP 2 LAST PACK_TYPE C0201
J 2
(-750 3150);
DISPLAY 0.553191 (-750 3150);
DISPLAY INVISIBLE (-750 3150);
FORCEPROP 1 LAST MATERIAL X6S
J 2
(-566 3179);
DISPLAY 0.574468 (-566 3179);
PAINT GREEN (-566 3179);
DISPLAY INVISIBLE (-566 3179);
FORCEPROP 2 LAST VOLTAGE 6.3V
J 2
(-925 3150);
DISPLAY 0.553191 (-925 3150);
DISPLAY INVISIBLE (-925 3150);
FORCEPROP 1 LAST PIN_NAMES_ROTATE TRUE
J 2
(-575 3100);
DISPLAY 0.489362 (-575 3100);
PAINT GREEN (-575 3100);
DISPLAY INVISIBLE (-575 3100);
FORCEPROP 2 LAST CDS_LIB pure_quanta
J 2
(-575 3100);
DISPLAY INVISIBLE (-575 3100);
FORCEPROP 1 LAST CDS_LMAN_SYM_OUTLINE -25,50,25,-50
J 2
(-575 3100);
DISPLAY 0.468085 (-575 3100);
PAINT GREEN (-575 3100);
DISPLAY INVISIBLE (-575 3100);
FORCEPROP 1 LAST PATH I61
J 2
(-575 3100);
DISPLAY 0.723404 (-575 3100);
DISPLAY INVISIBLE (-575 3100);
FORCEPROP 1 LAST $LOCATION C909
J 0
(-325 3175);
DISPLAY 1.021277 (-325 3175);
DISPLAY INVISIBLE (-325 3175);
FORCEPROP 2 LAST CDS_LOCATION C909
J 0
(-325 3175);
DISPLAY 1.021277 (-325 3175);
DISPLAY INVISIBLE (-325 3175);
FORCEPROP 2 LAST $SEC 1
J 2
(-400 3175);
DISPLAY 0.680851 (-400 3175);
PAINT MONO (-400 3175);
DISPLAY INVISIBLE (-400 3175);
FORCEPROP 2 LAST CDS_SEC 1
J 2
(-400 3175);
DISPLAY 0.680851 (-400 3175);
DISPLAY INVISIBLE (-400 3175);
FORCEADD Q_CAP_DIFFBUS..2
R 2
(-575 3150);
FORCEPROP 1 LAST PART_NUMBER SP_CH4221MEE01
J 2
(-691 3238);
DISPLAY 0.574468 (-691 3238);
PAINT GREEN (-691 3238);
DISPLAY INVISIBLE (-691 3238);
FORCEPROP 2 LAST VALUE DIFF BUS_0.22UF
J 2
(-725 3150);
DISPLAY 0.553191 (-725 3150);
FORCEPROP 1 LAST $LOCATION C908
J 2
(-341 3167);
DISPLAY 0.723404 (-341 3167);
PAINT GREEN (-341 3167);
FORCEPROP 2 LASTPIN (-500 3150) $PN 1
J 0
(-490 3160);
DISPLAY 0.808511 (-490 3160);
FORCEPROP 2 LASTPIN (-650 3150) $PN 2
J 2
(-660 3160);
DISPLAY 0.808511 (-660 3160);
FORCEPROP 2 LAST TOLERANCE 20%
J 2
(-650 3200);
DISPLAY 0.553191 (-650 3200);
DISPLAY INVISIBLE (-650 3200);
FORCEPROP 2 LAST PACK_TYPE C0201
J 2
(-750 3200);
DISPLAY 0.553191 (-750 3200);
DISPLAY INVISIBLE (-750 3200);
FORCEPROP 1 LAST MATERIAL X6S
J 2
(-566 3229);
DISPLAY 0.574468 (-566 3229);
PAINT GREEN (-566 3229);
DISPLAY INVISIBLE (-566 3229);
FORCEPROP 2 LAST VOLTAGE 6.3V
J 2
(-925 3200);
DISPLAY 0.553191 (-925 3200);
DISPLAY INVISIBLE (-925 3200);
FORCEPROP 1 LAST PIN_NAMES_ROTATE TRUE
J 2
(-575 3150);
DISPLAY 0.489362 (-575 3150);
PAINT GREEN (-575 3150);
DISPLAY INVISIBLE (-575 3150);
FORCEPROP 2 LAST CDS_LIB pure_quanta
J 2
(-575 3150);
DISPLAY INVISIBLE (-575 3150);
FORCEPROP 1 LAST CDS_LMAN_SYM_OUTLINE -25,50,25,-50
J 2
(-575 3150);
DISPLAY 0.468085 (-575 3150);
PAINT GREEN (-575 3150);
DISPLAY INVISIBLE (-575 3150);
FORCEPROP 1 LAST PATH I62
J 2
(-575 3150);
DISPLAY 0.723404 (-575 3150);
DISPLAY INVISIBLE (-575 3150);
FORCEPROP 1 LAST $LOCATION C908
J 0
(-325 3225);
DISPLAY 1.021277 (-325 3225);
DISPLAY INVISIBLE (-325 3225);
FORCEPROP 2 LAST CDS_LOCATION C908
J 0
(-325 3225);
DISPLAY 1.021277 (-325 3225);
DISPLAY INVISIBLE (-325 3225);
FORCEPROP 2 LAST $SEC 1
J 2
(-400 3225);
DISPLAY 0.680851 (-400 3225);
PAINT MONO (-400 3225);
DISPLAY INVISIBLE (-400 3225);
FORCEPROP 2 LAST CDS_SEC 1
J 2
(-400 3225);
DISPLAY 0.680851 (-400 3225);
DISPLAY INVISIBLE (-400 3225);
FORCEADD Q_CAP_DIFFBUS..2
R 2
(-575 3350);
FORCEPROP 1 LAST PART_NUMBER SP_CH4221MEE01
J 2
(-691 3438);
DISPLAY 0.574468 (-691 3438);
PAINT GREEN (-691 3438);
DISPLAY INVISIBLE (-691 3438);
FORCEPROP 2 LAST VALUE DIFF BUS_0.22UF
J 2
(-725 3350);
DISPLAY 0.553191 (-725 3350);
FORCEPROP 1 LAST $LOCATION C906
J 2
(-341 3367);
DISPLAY 0.723404 (-341 3367);
PAINT GREEN (-341 3367);
FORCEPROP 2 LASTPIN (-500 3350) $PN 1
J 0
(-490 3360);
DISPLAY 0.808511 (-490 3360);
FORCEPROP 2 LASTPIN (-650 3350) $PN 2
J 2
(-660 3360);
DISPLAY 0.808511 (-660 3360);
FORCEPROP 2 LAST TOLERANCE 20%
J 2
(-650 3400);
DISPLAY 0.553191 (-650 3400);
DISPLAY INVISIBLE (-650 3400);
FORCEPROP 2 LAST PACK_TYPE C0201
J 2
(-750 3400);
DISPLAY 0.553191 (-750 3400);
DISPLAY INVISIBLE (-750 3400);
FORCEPROP 1 LAST MATERIAL X6S
J 2
(-566 3429);
DISPLAY 0.574468 (-566 3429);
PAINT GREEN (-566 3429);
DISPLAY INVISIBLE (-566 3429);
FORCEPROP 2 LAST VOLTAGE 6.3V
J 2
(-925 3400);
DISPLAY 0.553191 (-925 3400);
DISPLAY INVISIBLE (-925 3400);
FORCEPROP 1 LAST PIN_NAMES_ROTATE TRUE
J 2
(-575 3350);
DISPLAY 0.489362 (-575 3350);
PAINT GREEN (-575 3350);
DISPLAY INVISIBLE (-575 3350);
FORCEPROP 2 LAST CDS_LIB pure_quanta
J 2
(-575 3350);
DISPLAY INVISIBLE (-575 3350);
FORCEPROP 1 LAST CDS_LMAN_SYM_OUTLINE -25,50,25,-50
J 2
(-575 3350);
DISPLAY 0.468085 (-575 3350);
PAINT GREEN (-575 3350);
DISPLAY INVISIBLE (-575 3350);
FORCEPROP 1 LAST PATH I63
J 2
(-575 3350);
DISPLAY 0.723404 (-575 3350);
DISPLAY INVISIBLE (-575 3350);
FORCEPROP 1 LAST $LOCATION C906
J 0
(-325 3425);
DISPLAY 1.021277 (-325 3425);
DISPLAY INVISIBLE (-325 3425);
FORCEPROP 2 LAST CDS_LOCATION C906
J 0
(-325 3425);
DISPLAY 1.021277 (-325 3425);
DISPLAY INVISIBLE (-325 3425);
FORCEPROP 2 LAST $SEC 1
J 2
(-400 3425);
DISPLAY 0.680851 (-400 3425);
PAINT MONO (-400 3425);
DISPLAY INVISIBLE (-400 3425);
FORCEPROP 2 LAST CDS_SEC 1
J 2
(-400 3425);
DISPLAY 0.680851 (-400 3425);
DISPLAY INVISIBLE (-400 3425);
FORCEADD Q_CAP_DIFFBUS..2
R 2
(-575 3300);
FORCEPROP 1 LAST PART_NUMBER SP_CH4221MEE01
J 2
(-691 3388);
DISPLAY 0.574468 (-691 3388);
PAINT GREEN (-691 3388);
DISPLAY INVISIBLE (-691 3388);
FORCEPROP 2 LAST VALUE DIFF BUS_0.22UF
J 2
(-725 3300);
DISPLAY 0.553191 (-725 3300);
FORCEPROP 1 LAST $LOCATION C907
J 2
(-341 3317);
DISPLAY 0.723404 (-341 3317);
PAINT GREEN (-341 3317);
FORCEPROP 2 LASTPIN (-500 3300) $PN 1
J 0
(-490 3310);
DISPLAY 0.808511 (-490 3310);
FORCEPROP 2 LASTPIN (-650 3300) $PN 2
J 2
(-660 3310);
DISPLAY 0.808511 (-660 3310);
FORCEPROP 2 LAST TOLERANCE 20%
J 2
(-650 3350);
DISPLAY 0.553191 (-650 3350);
DISPLAY INVISIBLE (-650 3350);
FORCEPROP 2 LAST PACK_TYPE C0201
J 2
(-750 3350);
DISPLAY 0.553191 (-750 3350);
DISPLAY INVISIBLE (-750 3350);
FORCEPROP 1 LAST MATERIAL X6S
J 2
(-566 3379);
DISPLAY 0.574468 (-566 3379);
PAINT GREEN (-566 3379);
DISPLAY INVISIBLE (-566 3379);
FORCEPROP 2 LAST VOLTAGE 6.3V
J 2
(-925 3350);
DISPLAY 0.553191 (-925 3350);
DISPLAY INVISIBLE (-925 3350);
FORCEPROP 1 LAST PIN_NAMES_ROTATE TRUE
J 2
(-575 3300);
DISPLAY 0.489362 (-575 3300);
PAINT GREEN (-575 3300);
DISPLAY INVISIBLE (-575 3300);
FORCEPROP 2 LAST CDS_LIB pure_quanta
J 2
(-575 3300);
DISPLAY INVISIBLE (-575 3300);
FORCEPROP 1 LAST CDS_LMAN_SYM_OUTLINE -25,50,25,-50
J 2
(-575 3300);
DISPLAY 0.468085 (-575 3300);
PAINT GREEN (-575 3300);
DISPLAY INVISIBLE (-575 3300);
FORCEPROP 1 LAST PATH I64
J 2
(-575 3300);
DISPLAY 0.723404 (-575 3300);
DISPLAY INVISIBLE (-575 3300);
FORCEPROP 1 LAST $LOCATION C907
J 0
(-325 3375);
DISPLAY 1.021277 (-325 3375);
DISPLAY INVISIBLE (-325 3375);
FORCEPROP 2 LAST CDS_LOCATION C907
J 0
(-325 3375);
DISPLAY 1.021277 (-325 3375);
DISPLAY INVISIBLE (-325 3375);
FORCEPROP 2 LAST $SEC 1
J 2
(-400 3375);
DISPLAY 0.680851 (-400 3375);
PAINT MONO (-400 3375);
DISPLAY INVISIBLE (-400 3375);
FORCEPROP 2 LAST CDS_SEC 1
J 2
(-400 3375);
DISPLAY 0.680851 (-400 3375);
DISPLAY INVISIBLE (-400 3375);
FORCEADD Q_CAP_DIFFBUS..2
R 2
(-575 3500);
FORCEPROP 1 LAST PART_NUMBER SP_CH4221MEE01
J 2
(-691 3588);
DISPLAY 0.574468 (-691 3588);
PAINT GREEN (-691 3588);
DISPLAY INVISIBLE (-691 3588);
FORCEPROP 2 LAST VALUE DIFF BUS_0.22UF
J 2
(-725 3500);
DISPLAY 0.553191 (-725 3500);
FORCEPROP 1 LAST $LOCATION C905
J 2
(-341 3517);
DISPLAY 0.723404 (-341 3517);
PAINT GREEN (-341 3517);
FORCEPROP 2 LASTPIN (-500 3500) $PN 1
J 0
(-490 3510);
DISPLAY 0.808511 (-490 3510);
FORCEPROP 2 LASTPIN (-650 3500) $PN 2
J 2
(-660 3510);
DISPLAY 0.808511 (-660 3510);
FORCEPROP 2 LAST TOLERANCE 20%
J 2
(-650 3550);
DISPLAY 0.553191 (-650 3550);
DISPLAY INVISIBLE (-650 3550);
FORCEPROP 2 LAST PACK_TYPE C0201
J 2
(-750 3550);
DISPLAY 0.553191 (-750 3550);
DISPLAY INVISIBLE (-750 3550);
FORCEPROP 1 LAST MATERIAL X6S
J 2
(-566 3579);
DISPLAY 0.574468 (-566 3579);
PAINT GREEN (-566 3579);
DISPLAY INVISIBLE (-566 3579);
FORCEPROP 2 LAST VOLTAGE 6.3V
J 2
(-925 3550);
DISPLAY 0.553191 (-925 3550);
DISPLAY INVISIBLE (-925 3550);
FORCEPROP 1 LAST PIN_NAMES_ROTATE TRUE
J 2
(-575 3500);
DISPLAY 0.489362 (-575 3500);
PAINT GREEN (-575 3500);
DISPLAY INVISIBLE (-575 3500);
FORCEPROP 2 LAST CDS_LIB pure_quanta
J 2
(-575 3500);
DISPLAY INVISIBLE (-575 3500);
FORCEPROP 1 LAST CDS_LMAN_SYM_OUTLINE -25,50,25,-50
J 2
(-575 3500);
DISPLAY 0.468085 (-575 3500);
PAINT GREEN (-575 3500);
DISPLAY INVISIBLE (-575 3500);
FORCEPROP 1 LAST PATH I65
J 2
(-575 3500);
DISPLAY 0.723404 (-575 3500);
DISPLAY INVISIBLE (-575 3500);
FORCEPROP 1 LAST $LOCATION C905
J 0
(-325 3575);
DISPLAY 1.021277 (-325 3575);
DISPLAY INVISIBLE (-325 3575);
FORCEPROP 2 LAST CDS_LOCATION C905
J 0
(-325 3575);
DISPLAY 1.021277 (-325 3575);
DISPLAY INVISIBLE (-325 3575);
FORCEPROP 2 LAST $SEC 1
J 2
(-400 3575);
DISPLAY 0.680851 (-400 3575);
PAINT MONO (-400 3575);
DISPLAY INVISIBLE (-400 3575);
FORCEPROP 2 LAST CDS_SEC 1
J 2
(-400 3575);
DISPLAY 0.680851 (-400 3575);
DISPLAY INVISIBLE (-400 3575);
FORCEADD Q_CAP_DIFFBUS..2
R 2
(-575 3550);
FORCEPROP 1 LAST PART_NUMBER SP_CH4221MEE01
J 2
(-691 3638);
DISPLAY 0.574468 (-691 3638);
PAINT GREEN (-691 3638);
DISPLAY INVISIBLE (-691 3638);
FORCEPROP 2 LAST VALUE DIFF BUS_0.22UF
J 2
(-725 3550);
DISPLAY 0.553191 (-725 3550);
FORCEPROP 1 LAST $LOCATION C904
J 2
(-341 3567);
DISPLAY 0.723404 (-341 3567);
PAINT GREEN (-341 3567);
FORCEPROP 2 LASTPIN (-500 3550) $PN 1
J 0
(-490 3560);
DISPLAY 0.808511 (-490 3560);
FORCEPROP 2 LASTPIN (-650 3550) $PN 2
J 2
(-660 3560);
DISPLAY 0.808511 (-660 3560);
FORCEPROP 2 LAST TOLERANCE 20%
J 2
(-650 3600);
DISPLAY 0.553191 (-650 3600);
DISPLAY INVISIBLE (-650 3600);
FORCEPROP 2 LAST PACK_TYPE C0201
J 2
(-750 3600);
DISPLAY 0.553191 (-750 3600);
DISPLAY INVISIBLE (-750 3600);
FORCEPROP 1 LAST MATERIAL X6S
J 2
(-566 3629);
DISPLAY 0.574468 (-566 3629);
PAINT GREEN (-566 3629);
DISPLAY INVISIBLE (-566 3629);
FORCEPROP 2 LAST VOLTAGE 6.3V
J 2
(-925 3600);
DISPLAY 0.553191 (-925 3600);
DISPLAY INVISIBLE (-925 3600);
FORCEPROP 1 LAST PIN_NAMES_ROTATE TRUE
J 2
(-575 3550);
DISPLAY 0.489362 (-575 3550);
PAINT GREEN (-575 3550);
DISPLAY INVISIBLE (-575 3550);
FORCEPROP 2 LAST CDS_LIB pure_quanta
J 2
(-575 3550);
DISPLAY INVISIBLE (-575 3550);
FORCEPROP 1 LAST CDS_LMAN_SYM_OUTLINE -25,50,25,-50
J 2
(-575 3550);
DISPLAY 0.468085 (-575 3550);
PAINT GREEN (-575 3550);
DISPLAY INVISIBLE (-575 3550);
FORCEPROP 1 LAST PATH I66
J 2
(-575 3550);
DISPLAY 0.723404 (-575 3550);
DISPLAY INVISIBLE (-575 3550);
FORCEPROP 1 LAST $LOCATION C904
J 0
(-325 3625);
DISPLAY 1.021277 (-325 3625);
DISPLAY INVISIBLE (-325 3625);
FORCEPROP 2 LAST CDS_LOCATION C904
J 0
(-325 3625);
DISPLAY 1.021277 (-325 3625);
DISPLAY INVISIBLE (-325 3625);
FORCEPROP 2 LAST $SEC 1
J 2
(-400 3625);
DISPLAY 0.680851 (-400 3625);
PAINT MONO (-400 3625);
DISPLAY INVISIBLE (-400 3625);
FORCEPROP 2 LAST CDS_SEC 1
J 2
(-400 3625);
DISPLAY 0.680851 (-400 3625);
DISPLAY INVISIBLE (-400 3625);
FORCEADD Q_CAP_DIFFBUS..2
R 2
(-575 3700);
FORCEPROP 1 LAST PART_NUMBER SP_CH4221MEE01
J 2
(-691 3788);
DISPLAY 0.574468 (-691 3788);
PAINT GREEN (-691 3788);
DISPLAY INVISIBLE (-691 3788);
FORCEPROP 2 LAST VALUE DIFF BUS_0.22UF
J 2
(-725 3700);
DISPLAY 0.553191 (-725 3700);
FORCEPROP 1 LAST $LOCATION C903
J 2
(-341 3717);
DISPLAY 0.723404 (-341 3717);
PAINT GREEN (-341 3717);
FORCEPROP 2 LASTPIN (-500 3700) $PN 1
J 0
(-490 3710);
DISPLAY 0.808511 (-490 3710);
FORCEPROP 2 LASTPIN (-650 3700) $PN 2
J 2
(-660 3710);
DISPLAY 0.808511 (-660 3710);
FORCEPROP 2 LAST TOLERANCE 20%
J 2
(-650 3750);
DISPLAY 0.553191 (-650 3750);
DISPLAY INVISIBLE (-650 3750);
FORCEPROP 2 LAST PACK_TYPE C0201
J 2
(-750 3750);
DISPLAY 0.553191 (-750 3750);
DISPLAY INVISIBLE (-750 3750);
FORCEPROP 1 LAST MATERIAL X6S
J 2
(-566 3779);
DISPLAY 0.574468 (-566 3779);
PAINT GREEN (-566 3779);
DISPLAY INVISIBLE (-566 3779);
FORCEPROP 2 LAST VOLTAGE 6.3V
J 2
(-925 3750);
DISPLAY 0.553191 (-925 3750);
DISPLAY INVISIBLE (-925 3750);
FORCEPROP 1 LAST PIN_NAMES_ROTATE TRUE
J 2
(-575 3700);
DISPLAY 0.489362 (-575 3700);
PAINT GREEN (-575 3700);
DISPLAY INVISIBLE (-575 3700);
FORCEPROP 2 LAST CDS_LIB pure_quanta
J 2
(-575 3700);
DISPLAY INVISIBLE (-575 3700);
FORCEPROP 1 LAST CDS_LMAN_SYM_OUTLINE -25,50,25,-50
J 2
(-575 3700);
DISPLAY 0.468085 (-575 3700);
PAINT GREEN (-575 3700);
DISPLAY INVISIBLE (-575 3700);
FORCEPROP 1 LAST PATH I67
J 2
(-575 3700);
DISPLAY 0.723404 (-575 3700);
DISPLAY INVISIBLE (-575 3700);
FORCEPROP 1 LAST $LOCATION C903
J 0
(-325 3775);
DISPLAY 1.021277 (-325 3775);
DISPLAY INVISIBLE (-325 3775);
FORCEPROP 2 LAST CDS_LOCATION C903
J 0
(-325 3775);
DISPLAY 1.021277 (-325 3775);
DISPLAY INVISIBLE (-325 3775);
FORCEPROP 2 LAST $SEC 1
J 2
(-400 3775);
DISPLAY 0.680851 (-400 3775);
PAINT MONO (-400 3775);
DISPLAY INVISIBLE (-400 3775);
FORCEPROP 2 LAST CDS_SEC 1
J 2
(-400 3775);
DISPLAY 0.680851 (-400 3775);
DISPLAY INVISIBLE (-400 3775);
FORCEADD Q_CAP_DIFFBUS..2
R 2
(-575 3750);
FORCEPROP 1 LAST PART_NUMBER SP_CH4221MEE01
J 2
(-391 3838);
DISPLAY 0.574468 (-391 3838);
PAINT GREEN (-391 3838);
DISPLAY INVISIBLE (-391 3838);
FORCEPROP 2 LAST PACK_TYPE C0201
J 2
(-625 3900);
DISPLAY 0.553191 (-625 3900);
PAINT GREEN (-625 3900);
FORCEPROP 2 LAST VALUE DIFF BUS_0.22UF
J 2
(-725 3750);
DISPLAY 0.553191 (-725 3750);
FORCEPROP 2 LAST VOLTAGE 6.3V
J 2
(-400 3900);
DISPLAY 0.553191 (-400 3900);
PAINT GREEN (-400 3900);
FORCEPROP 2 LAST TOLERANCE 20%
J 2
(-525 3900);
DISPLAY 0.553191 (-525 3900);
PAINT GREEN (-525 3900);
FORCEPROP 1 LAST MATERIAL X6S
J 2
(-666 3954);
DISPLAY 0.574468 (-666 3954);
PAINT GREEN (-666 3954);
FORCEPROP 1 LAST $LOCATION C902
J 2
(-341 3767);
DISPLAY 0.723404 (-341 3767);
PAINT GREEN (-341 3767);
FORCEPROP 2 LASTPIN (-500 3750) $PN 1
J 0
(-490 3760);
DISPLAY 0.808511 (-490 3760);
FORCEPROP 2 LASTPIN (-650 3750) $PN 2
J 2
(-660 3760);
DISPLAY 0.808511 (-660 3760);
FORCEPROP 1 LAST PIN_NAMES_ROTATE TRUE
J 2
(-575 3750);
DISPLAY 0.489362 (-575 3750);
PAINT GREEN (-575 3750);
DISPLAY INVISIBLE (-575 3750);
FORCEPROP 1 LAST CDS_LMAN_SYM_OUTLINE -25,50,25,-50
J 2
(-575 3750);
DISPLAY 0.468085 (-575 3750);
PAINT GREEN (-575 3750);
DISPLAY INVISIBLE (-575 3750);
FORCEPROP 2 LAST CDS_LIB pure_quanta
J 2
(-575 3750);
DISPLAY INVISIBLE (-575 3750);
FORCEPROP 1 LAST PATH I68
J 2
(-575 3750);
DISPLAY 0.723404 (-575 3750);
DISPLAY INVISIBLE (-575 3750);
FORCEPROP 1 LAST $LOCATION C902
J 0
(-325 3825);
DISPLAY 1.021277 (-325 3825);
DISPLAY INVISIBLE (-325 3825);
FORCEPROP 2 LAST CDS_LOCATION C902
J 0
(-650 4000);
DISPLAY 1.021277 (-650 4000);
DISPLAY INVISIBLE (-650 4000);
FORCEPROP 2 LAST $SEC 1
J 2
(-400 3825);
DISPLAY 0.680851 (-400 3825);
PAINT MONO (-400 3825);
DISPLAY INVISIBLE (-400 3825);
FORCEPROP 2 LAST CDS_SEC 1
J 2
(-400 3825);
DISPLAY 0.680851 (-400 3825);
DISPLAY INVISIBLE (-400 3825);
FORCEADD TAP..1
(-25 3550);
FORCEPROP 3 LASTPIN (-75 3550) SIG_NAME P5E_CPU0_PE0_TX_C_DN<14>
J 0
(-65 3560);
DISPLAY 0.659574 (-65 3560);
PAINT MONO (-65 3560);
DISPLAY INVISIBLE (-65 3560);
FORCEPROP 1 LASTPIN (-75 3550) BN 14
J 0
(-87 3558);
DISPLAY 0.680851 (-87 3558);
PAINT GREEN (-87 3558);
FORCEPROP 2 LAST CDS_LIB standard
J 0
(-25 3550);
DISPLAY INVISIBLE (-25 3550);
FORCEPROP 1 LAST BODY_TYPE PLUMBING
J 0
(-25 3600);
DISPLAY 0.872340 (-25 3600);
PAINT GREEN (-25 3600);
DISPLAY INVISIBLE (-25 3600);
FORCEPROP 1 LAST HDL_TAP TRUE
J 0
(300 3425);
DISPLAY 0.872340 (300 3425);
DISPLAY INVISIBLE (300 3425);
FORCEPROP 1 LAST PATH I69
J 0
(-27 3550);
DISPLAY 0.872340 (-27 3550);
PAINT GREEN (-27 3550);
DISPLAY INVISIBLE (-27 3550);
FORCEADD TAP..1
R 2
(-1300 375);
FORCEPROP 3 LASTPIN (-1250 375) SIG_NAME P5E_CPU0_PE0_TX_DN<0>
J 0
(-1240 385);
DISPLAY 0.659574 (-1240 385);
PAINT MONO (-1240 385);
DISPLAY INVISIBLE (-1240 385);
FORCEPROP 1 LASTPIN (-1250 375) BN 0
J 2
(-1238 383);
DISPLAY 0.680851 (-1238 383);
PAINT GREEN (-1238 383);
FORCEPROP 2 LAST CDS_LIB standard
J 0
(-1300 375);
DISPLAY INVISIBLE (-1300 375);
FORCEPROP 1 LAST BODY_TYPE PLUMBING
J 2
(-1300 425);
DISPLAY 0.872340 (-1300 425);
PAINT GREEN (-1300 425);
DISPLAY INVISIBLE (-1300 425);
FORCEPROP 1 LAST HDL_TAP TRUE
J 2
(-1625 250);
DISPLAY 0.872340 (-1625 250);
DISPLAY INVISIBLE (-1625 250);
FORCEPROP 1 LAST PATH I7
J 2
(-1298 375);
DISPLAY 0.872340 (-1298 375);
PAINT GREEN (-1298 375);
DISPLAY INVISIBLE (-1298 375);
FORCEADD TAP..1
(-25 2950);
FORCEPROP 3 LASTPIN (-75 2950) SIG_NAME P5E_CPU0_PE0_TX_C_DN<11>
J 0
(-65 2960);
DISPLAY 0.659574 (-65 2960);
PAINT MONO (-65 2960);
DISPLAY INVISIBLE (-65 2960);
FORCEPROP 1 LASTPIN (-75 2950) BN 11
J 0
(-87 2958);
DISPLAY 0.680851 (-87 2958);
PAINT GREEN (-87 2958);
FORCEPROP 2 LAST CDS_LIB standard
J 0
(-25 2950);
DISPLAY INVISIBLE (-25 2950);
FORCEPROP 1 LAST BODY_TYPE PLUMBING
J 0
(-25 3000);
DISPLAY 0.872340 (-25 3000);
PAINT GREEN (-25 3000);
DISPLAY INVISIBLE (-25 3000);
FORCEPROP 1 LAST HDL_TAP TRUE
J 0
(300 2825);
DISPLAY 0.872340 (300 2825);
DISPLAY INVISIBLE (300 2825);
FORCEPROP 1 LAST PATH I70
J 0
(-27 2950);
DISPLAY 0.872340 (-27 2950);
PAINT GREEN (-27 2950);
DISPLAY INVISIBLE (-27 2950);
FORCEADD TAP..1
(-25 3350);
FORCEPROP 3 LASTPIN (-75 3350) SIG_NAME P5E_CPU0_PE0_TX_C_DN<13>
J 0
(-65 3360);
DISPLAY 0.659574 (-65 3360);
PAINT MONO (-65 3360);
DISPLAY INVISIBLE (-65 3360);
FORCEPROP 1 LASTPIN (-75 3350) BN 13
J 0
(-87 3358);
DISPLAY 0.680851 (-87 3358);
PAINT GREEN (-87 3358);
FORCEPROP 2 LAST CDS_LIB standard
J 0
(-25 3350);
DISPLAY INVISIBLE (-25 3350);
FORCEPROP 1 LAST BODY_TYPE PLUMBING
J 0
(-25 3400);
DISPLAY 0.872340 (-25 3400);
PAINT GREEN (-25 3400);
DISPLAY INVISIBLE (-25 3400);
FORCEPROP 1 LAST HDL_TAP TRUE
J 0
(300 3225);
DISPLAY 0.872340 (300 3225);
DISPLAY INVISIBLE (300 3225);
FORCEPROP 1 LAST PATH I71
J 0
(-27 3350);
DISPLAY 0.872340 (-27 3350);
PAINT GREEN (-27 3350);
DISPLAY INVISIBLE (-27 3350);
FORCEADD TAP..1
(-25 3150);
FORCEPROP 3 LASTPIN (-75 3150) SIG_NAME P5E_CPU0_PE0_TX_C_DN<12>
J 0
(-65 3160);
DISPLAY 0.659574 (-65 3160);
PAINT MONO (-65 3160);
DISPLAY INVISIBLE (-65 3160);
FORCEPROP 1 LASTPIN (-75 3150) BN 12
J 0
(-87 3158);
DISPLAY 0.680851 (-87 3158);
PAINT GREEN (-87 3158);
FORCEPROP 2 LAST CDS_LIB standard
J 0
(-25 3150);
DISPLAY INVISIBLE (-25 3150);
FORCEPROP 1 LAST BODY_TYPE PLUMBING
J 0
(-25 3200);
DISPLAY 0.872340 (-25 3200);
PAINT GREEN (-25 3200);
DISPLAY INVISIBLE (-25 3200);
FORCEPROP 1 LAST HDL_TAP TRUE
J 0
(300 3025);
DISPLAY 0.872340 (300 3025);
DISPLAY INVISIBLE (300 3025);
FORCEPROP 1 LAST PATH I72
J 0
(-27 3150);
DISPLAY 0.872340 (-27 3150);
PAINT GREEN (-27 3150);
DISPLAY INVISIBLE (-27 3150);
FORCEADD TAP..1
(-25 2750);
FORCEPROP 3 LASTPIN (-75 2750) SIG_NAME P5E_CPU0_PE0_TX_C_DN<10>
J 0
(-65 2760);
DISPLAY 0.659574 (-65 2760);
PAINT MONO (-65 2760);
DISPLAY INVISIBLE (-65 2760);
FORCEPROP 1 LASTPIN (-75 2750) BN 10
J 0
(-87 2758);
DISPLAY 0.680851 (-87 2758);
PAINT GREEN (-87 2758);
FORCEPROP 2 LAST CDS_LIB standard
J 0
(-25 2750);
DISPLAY INVISIBLE (-25 2750);
FORCEPROP 1 LAST BODY_TYPE PLUMBING
J 0
(-25 2800);
DISPLAY 0.872340 (-25 2800);
PAINT GREEN (-25 2800);
DISPLAY INVISIBLE (-25 2800);
FORCEPROP 1 LAST HDL_TAP TRUE
J 0
(300 2625);
DISPLAY 0.872340 (300 2625);
DISPLAY INVISIBLE (300 2625);
FORCEPROP 1 LAST PATH I73
J 0
(-27 2750);
DISPLAY 0.872340 (-27 2750);
PAINT GREEN (-27 2750);
DISPLAY INVISIBLE (-27 2750);
FORCEADD TAP..1
(-25 2350);
FORCEPROP 3 LASTPIN (-75 2350) SIG_NAME P5E_CPU0_PE0_TX_C_DN<8>
J 0
(-65 2360);
DISPLAY 0.659574 (-65 2360);
PAINT MONO (-65 2360);
DISPLAY INVISIBLE (-65 2360);
FORCEPROP 1 LASTPIN (-75 2350) BN 8
J 0
(-87 2358);
DISPLAY 0.680851 (-87 2358);
PAINT GREEN (-87 2358);
FORCEPROP 2 LAST CDS_LIB standard
J 0
(-25 2350);
DISPLAY INVISIBLE (-25 2350);
FORCEPROP 1 LAST BODY_TYPE PLUMBING
J 0
(-25 2400);
DISPLAY 0.872340 (-25 2400);
PAINT GREEN (-25 2400);
DISPLAY INVISIBLE (-25 2400);
FORCEPROP 1 LAST HDL_TAP TRUE
J 0
(300 2225);
DISPLAY 0.872340 (300 2225);
DISPLAY INVISIBLE (300 2225);
FORCEPROP 1 LAST PATH I74
J 0
(-27 2350);
DISPLAY 0.872340 (-27 2350);
PAINT GREEN (-27 2350);
DISPLAY INVISIBLE (-27 2350);
FORCEADD TAP..1
(-25 2550);
FORCEPROP 3 LASTPIN (-75 2550) SIG_NAME P5E_CPU0_PE0_TX_C_DN<9>
J 0
(-65 2560);
DISPLAY 0.659574 (-65 2560);
PAINT MONO (-65 2560);
DISPLAY INVISIBLE (-65 2560);
FORCEPROP 1 LASTPIN (-75 2550) BN 9
J 0
(-87 2558);
DISPLAY 0.680851 (-87 2558);
PAINT GREEN (-87 2558);
FORCEPROP 2 LAST CDS_LIB standard
J 0
(-25 2550);
DISPLAY INVISIBLE (-25 2550);
FORCEPROP 1 LAST BODY_TYPE PLUMBING
J 0
(-25 2600);
DISPLAY 0.872340 (-25 2600);
PAINT GREEN (-25 2600);
DISPLAY INVISIBLE (-25 2600);
FORCEPROP 1 LAST HDL_TAP TRUE
J 0
(300 2425);
DISPLAY 0.872340 (300 2425);
DISPLAY INVISIBLE (300 2425);
FORCEPROP 1 LAST PATH I75
J 0
(-27 2550);
DISPLAY 0.872340 (-27 2550);
PAINT GREEN (-27 2550);
DISPLAY INVISIBLE (-27 2550);
FORCEADD TAP..1
(-25 1775);
FORCEPROP 3 LASTPIN (-75 1775) SIG_NAME P5E_CPU0_PE0_TX_C_DN<7>
J 0
(-65 1785);
DISPLAY 0.659574 (-65 1785);
PAINT MONO (-65 1785);
DISPLAY INVISIBLE (-65 1785);
FORCEPROP 1 LASTPIN (-75 1775) BN 7
J 0
(-87 1783);
DISPLAY 0.680851 (-87 1783);
PAINT GREEN (-87 1783);
FORCEPROP 2 LAST CDS_LIB standard
J 0
(-25 1775);
DISPLAY INVISIBLE (-25 1775);
FORCEPROP 1 LAST BODY_TYPE PLUMBING
J 0
(-25 1825);
DISPLAY 0.872340 (-25 1825);
PAINT GREEN (-25 1825);
DISPLAY INVISIBLE (-25 1825);
FORCEPROP 1 LAST HDL_TAP TRUE
J 0
(300 1650);
DISPLAY 0.872340 (300 1650);
DISPLAY INVISIBLE (300 1650);
FORCEPROP 1 LAST PATH I76
J 0
(-27 1775);
DISPLAY 0.872340 (-27 1775);
PAINT GREEN (-27 1775);
DISPLAY INVISIBLE (-27 1775);
FORCEADD TAP..1
(-25 1375);
FORCEPROP 3 LASTPIN (-75 1375) SIG_NAME P5E_CPU0_PE0_TX_C_DN<5>
J 0
(-65 1385);
DISPLAY 0.659574 (-65 1385);
PAINT MONO (-65 1385);
DISPLAY INVISIBLE (-65 1385);
FORCEPROP 1 LASTPIN (-75 1375) BN 5
J 0
(-87 1383);
DISPLAY 0.680851 (-87 1383);
PAINT GREEN (-87 1383);
FORCEPROP 2 LAST CDS_LIB standard
J 0
(-25 1375);
DISPLAY INVISIBLE (-25 1375);
FORCEPROP 1 LAST BODY_TYPE PLUMBING
J 0
(-25 1425);
DISPLAY 0.872340 (-25 1425);
PAINT GREEN (-25 1425);
DISPLAY INVISIBLE (-25 1425);
FORCEPROP 1 LAST HDL_TAP TRUE
J 0
(300 1250);
DISPLAY 0.872340 (300 1250);
DISPLAY INVISIBLE (300 1250);
FORCEPROP 1 LAST PATH I77
J 0
(-27 1375);
DISPLAY 0.872340 (-27 1375);
PAINT GREEN (-27 1375);
DISPLAY INVISIBLE (-27 1375);
FORCEADD TAP..1
(-25 1575);
FORCEPROP 3 LASTPIN (-75 1575) SIG_NAME P5E_CPU0_PE0_TX_C_DN<6>
J 0
(-65 1585);
DISPLAY 0.659574 (-65 1585);
PAINT MONO (-65 1585);
DISPLAY INVISIBLE (-65 1585);
FORCEPROP 1 LASTPIN (-75 1575) BN 6
J 0
(-87 1583);
DISPLAY 0.680851 (-87 1583);
PAINT GREEN (-87 1583);
FORCEPROP 2 LAST CDS_LIB standard
J 0
(-25 1575);
DISPLAY INVISIBLE (-25 1575);
FORCEPROP 1 LAST BODY_TYPE PLUMBING
J 0
(-25 1625);
DISPLAY 0.872340 (-25 1625);
PAINT GREEN (-25 1625);
DISPLAY INVISIBLE (-25 1625);
FORCEPROP 1 LAST HDL_TAP TRUE
J 0
(300 1450);
DISPLAY 0.872340 (300 1450);
DISPLAY INVISIBLE (300 1450);
FORCEPROP 1 LAST PATH I78
J 0
(-27 1575);
DISPLAY 0.872340 (-27 1575);
PAINT GREEN (-27 1575);
DISPLAY INVISIBLE (-27 1575);
FORCEADD TAP..1
(-25 975);
FORCEPROP 3 LASTPIN (-75 975) SIG_NAME P5E_CPU0_PE0_TX_C_DN<3>
J 0
(-65 985);
DISPLAY 0.659574 (-65 985);
PAINT MONO (-65 985);
DISPLAY INVISIBLE (-65 985);
FORCEPROP 1 LASTPIN (-75 975) BN 3
J 0
(-87 983);
DISPLAY 0.680851 (-87 983);
PAINT GREEN (-87 983);
FORCEPROP 2 LAST CDS_LIB standard
J 0
(-25 975);
DISPLAY INVISIBLE (-25 975);
FORCEPROP 1 LAST BODY_TYPE PLUMBING
J 0
(-25 1025);
DISPLAY 0.872340 (-25 1025);
PAINT GREEN (-25 1025);
DISPLAY INVISIBLE (-25 1025);
FORCEPROP 1 LAST HDL_TAP TRUE
J 0
(300 850);
DISPLAY 0.872340 (300 850);
DISPLAY INVISIBLE (300 850);
FORCEPROP 1 LAST PATH I79
J 0
(-27 975);
DISPLAY 0.872340 (-27 975);
PAINT GREEN (-27 975);
DISPLAY INVISIBLE (-27 975);
FORCEADD TAP..1
R 2
(-1300 575);
FORCEPROP 3 LASTPIN (-1250 575) SIG_NAME P5E_CPU0_PE0_TX_DN<1>
J 0
(-1240 585);
DISPLAY 0.659574 (-1240 585);
PAINT MONO (-1240 585);
DISPLAY INVISIBLE (-1240 585);
FORCEPROP 1 LASTPIN (-1250 575) BN 1
J 2
(-1238 583);
DISPLAY 0.680851 (-1238 583);
PAINT GREEN (-1238 583);
FORCEPROP 2 LAST CDS_LIB standard
J 0
(-1300 575);
DISPLAY INVISIBLE (-1300 575);
FORCEPROP 1 LAST BODY_TYPE PLUMBING
J 2
(-1300 625);
DISPLAY 0.872340 (-1300 625);
PAINT GREEN (-1300 625);
DISPLAY INVISIBLE (-1300 625);
FORCEPROP 1 LAST HDL_TAP TRUE
J 2
(-1625 450);
DISPLAY 0.872340 (-1625 450);
DISPLAY INVISIBLE (-1625 450);
FORCEPROP 1 LAST PATH I8
J 2
(-1298 575);
DISPLAY 0.872340 (-1298 575);
PAINT GREEN (-1298 575);
DISPLAY INVISIBLE (-1298 575);
FORCEADD TAP..1
(-25 1175);
FORCEPROP 3 LASTPIN (-75 1175) SIG_NAME P5E_CPU0_PE0_TX_C_DN<4>
J 0
(-65 1185);
DISPLAY 0.659574 (-65 1185);
PAINT MONO (-65 1185);
DISPLAY INVISIBLE (-65 1185);
FORCEPROP 1 LASTPIN (-75 1175) BN 4
J 0
(-87 1183);
DISPLAY 0.680851 (-87 1183);
PAINT GREEN (-87 1183);
FORCEPROP 2 LAST CDS_LIB standard
J 0
(-25 1175);
DISPLAY INVISIBLE (-25 1175);
FORCEPROP 1 LAST BODY_TYPE PLUMBING
J 0
(-25 1225);
DISPLAY 0.872340 (-25 1225);
PAINT GREEN (-25 1225);
DISPLAY INVISIBLE (-25 1225);
FORCEPROP 1 LAST HDL_TAP TRUE
J 0
(300 1050);
DISPLAY 0.872340 (300 1050);
DISPLAY INVISIBLE (300 1050);
FORCEPROP 1 LAST PATH I80
J 0
(-27 1175);
DISPLAY 0.872340 (-27 1175);
PAINT GREEN (-27 1175);
DISPLAY INVISIBLE (-27 1175);
FORCEADD TAP..1
(-25 775);
FORCEPROP 3 LASTPIN (-75 775) SIG_NAME P5E_CPU0_PE0_TX_C_DN<2>
J 0
(-65 785);
DISPLAY 0.659574 (-65 785);
PAINT MONO (-65 785);
DISPLAY INVISIBLE (-65 785);
FORCEPROP 1 LASTPIN (-75 775) BN 2
J 0
(-87 783);
DISPLAY 0.680851 (-87 783);
PAINT GREEN (-87 783);
FORCEPROP 2 LAST CDS_LIB standard
J 0
(-25 775);
DISPLAY INVISIBLE (-25 775);
FORCEPROP 1 LAST BODY_TYPE PLUMBING
J 0
(-25 825);
DISPLAY 0.872340 (-25 825);
PAINT GREEN (-25 825);
DISPLAY INVISIBLE (-25 825);
FORCEPROP 1 LAST HDL_TAP TRUE
J 0
(300 650);
DISPLAY 0.872340 (300 650);
DISPLAY INVISIBLE (300 650);
FORCEPROP 1 LAST PATH I81
J 0
(-27 775);
DISPLAY 0.872340 (-27 775);
PAINT GREEN (-27 775);
DISPLAY INVISIBLE (-27 775);
FORCEADD TAP..1
(-25 575);
FORCEPROP 3 LASTPIN (-75 575) SIG_NAME P5E_CPU0_PE0_TX_C_DN<1>
J 0
(-65 585);
DISPLAY 0.659574 (-65 585);
PAINT MONO (-65 585);
DISPLAY INVISIBLE (-65 585);
FORCEPROP 1 LASTPIN (-75 575) BN 1
J 0
(-87 583);
DISPLAY 0.680851 (-87 583);
PAINT GREEN (-87 583);
FORCEPROP 2 LAST CDS_LIB standard
J 0
(-25 575);
DISPLAY INVISIBLE (-25 575);
FORCEPROP 1 LAST BODY_TYPE PLUMBING
J 0
(-25 625);
DISPLAY 0.872340 (-25 625);
PAINT GREEN (-25 625);
DISPLAY INVISIBLE (-25 625);
FORCEPROP 1 LAST HDL_TAP TRUE
J 0
(300 450);
DISPLAY 0.872340 (300 450);
DISPLAY INVISIBLE (300 450);
FORCEPROP 1 LAST PATH I82
J 0
(-27 575);
DISPLAY 0.872340 (-27 575);
PAINT GREEN (-27 575);
DISPLAY INVISIBLE (-27 575);
FORCEADD TAP..1
(-25 375);
FORCEPROP 3 LASTPIN (-75 375) SIG_NAME P5E_CPU0_PE0_TX_C_DN<0>
J 0
(-65 385);
DISPLAY 0.659574 (-65 385);
PAINT MONO (-65 385);
DISPLAY INVISIBLE (-65 385);
FORCEPROP 1 LASTPIN (-75 375) BN 0
J 0
(-87 383);
DISPLAY 0.680851 (-87 383);
PAINT GREEN (-87 383);
FORCEPROP 2 LAST CDS_LIB standard
J 0
(-25 375);
DISPLAY INVISIBLE (-25 375);
FORCEPROP 1 LAST BODY_TYPE PLUMBING
J 0
(-25 425);
DISPLAY 0.872340 (-25 425);
PAINT GREEN (-25 425);
DISPLAY INVISIBLE (-25 425);
FORCEPROP 1 LAST HDL_TAP TRUE
J 0
(300 250);
DISPLAY 0.872340 (300 250);
DISPLAY INVISIBLE (300 250);
FORCEPROP 1 LAST PATH I83
J 0
(-27 375);
DISPLAY 0.872340 (-27 375);
PAINT GREEN (-27 375);
DISPLAY INVISIBLE (-27 375);
FORCEADD TAP..1
(-25 3750);
FORCEPROP 3 LASTPIN (-75 3750) SIG_NAME P5E_CPU0_PE0_TX_C_DN<15>
J 0
(-65 3760);
DISPLAY 0.659574 (-65 3760);
PAINT MONO (-65 3760);
DISPLAY INVISIBLE (-65 3760);
FORCEPROP 1 LASTPIN (-75 3750) BN 15
J 0
(-87 3758);
DISPLAY 0.680851 (-87 3758);
PAINT GREEN (-87 3758);
FORCEPROP 2 LAST CDS_LIB standard
J 0
(-25 3750);
DISPLAY INVISIBLE (-25 3750);
FORCEPROP 1 LAST BODY_TYPE PLUMBING
J 0
(-25 3800);
DISPLAY 0.872340 (-25 3800);
PAINT GREEN (-25 3800);
DISPLAY INVISIBLE (-25 3800);
FORCEPROP 1 LAST HDL_TAP TRUE
J 0
(300 3625);
DISPLAY 0.872340 (300 3625);
DISPLAY INVISIBLE (300 3625);
FORCEPROP 1 LAST PATH I84
J 0
(-27 3750);
DISPLAY 0.872340 (-27 3750);
PAINT GREEN (-27 3750);
DISPLAY INVISIBLE (-27 3750);
FORCEADD TAP..1
(175 325);
FORCEPROP 3 LASTPIN (125 325) SIG_NAME P5E_CPU0_PE0_TX_C_DP<0>
J 0
(135 335);
DISPLAY 0.659574 (135 335);
PAINT MONO (135 335);
DISPLAY INVISIBLE (135 335);
FORCEPROP 1 LASTPIN (125 325) BN 0
J 0
(113 333);
DISPLAY 0.680851 (113 333);
PAINT GREEN (113 333);
FORCEPROP 2 LAST CDS_LIB standard
J 0
(175 325);
DISPLAY INVISIBLE (175 325);
FORCEPROP 1 LAST BODY_TYPE PLUMBING
J 0
(175 375);
DISPLAY 0.872340 (175 375);
PAINT GREEN (175 375);
DISPLAY INVISIBLE (175 375);
FORCEPROP 1 LAST HDL_TAP TRUE
J 0
(500 200);
DISPLAY 0.872340 (500 200);
DISPLAY INVISIBLE (500 200);
FORCEPROP 1 LAST PATH I85
J 0
(173 325);
DISPLAY 0.872340 (173 325);
PAINT GREEN (173 325);
DISPLAY INVISIBLE (173 325);
FORCEADD TAP..1
(175 525);
FORCEPROP 3 LASTPIN (125 525) SIG_NAME P5E_CPU0_PE0_TX_C_DP<1>
J 0
(135 535);
DISPLAY 0.659574 (135 535);
PAINT MONO (135 535);
DISPLAY INVISIBLE (135 535);
FORCEPROP 1 LASTPIN (125 525) BN 1
J 0
(113 533);
DISPLAY 0.680851 (113 533);
PAINT GREEN (113 533);
FORCEPROP 2 LAST CDS_LIB standard
J 0
(175 525);
DISPLAY INVISIBLE (175 525);
FORCEPROP 1 LAST BODY_TYPE PLUMBING
J 0
(175 575);
DISPLAY 0.872340 (175 575);
PAINT GREEN (175 575);
DISPLAY INVISIBLE (175 575);
FORCEPROP 1 LAST HDL_TAP TRUE
J 0
(500 400);
DISPLAY 0.872340 (500 400);
DISPLAY INVISIBLE (500 400);
FORCEPROP 1 LAST PATH I86
J 0
(173 525);
DISPLAY 0.872340 (173 525);
PAINT GREEN (173 525);
DISPLAY INVISIBLE (173 525);
FORCEADD TAP..1
(175 725);
FORCEPROP 3 LASTPIN (125 725) SIG_NAME P5E_CPU0_PE0_TX_C_DP<2>
J 0
(135 735);
DISPLAY 0.659574 (135 735);
PAINT MONO (135 735);
DISPLAY INVISIBLE (135 735);
FORCEPROP 1 LASTPIN (125 725) BN 2
J 0
(113 733);
DISPLAY 0.680851 (113 733);
PAINT GREEN (113 733);
FORCEPROP 2 LAST CDS_LIB standard
J 0
(175 725);
DISPLAY INVISIBLE (175 725);
FORCEPROP 1 LAST BODY_TYPE PLUMBING
J 0
(175 775);
DISPLAY 0.872340 (175 775);
PAINT GREEN (175 775);
DISPLAY INVISIBLE (175 775);
FORCEPROP 1 LAST HDL_TAP TRUE
J 0
(500 600);
DISPLAY 0.872340 (500 600);
DISPLAY INVISIBLE (500 600);
FORCEPROP 1 LAST PATH I87
J 0
(173 725);
DISPLAY 0.872340 (173 725);
PAINT GREEN (173 725);
DISPLAY INVISIBLE (173 725);
FORCEADD TAP..1
(175 925);
FORCEPROP 3 LASTPIN (125 925) SIG_NAME P5E_CPU0_PE0_TX_C_DP<3>
J 0
(135 935);
DISPLAY 0.659574 (135 935);
PAINT MONO (135 935);
DISPLAY INVISIBLE (135 935);
FORCEPROP 1 LASTPIN (125 925) BN 3
J 0
(113 933);
DISPLAY 0.680851 (113 933);
PAINT GREEN (113 933);
FORCEPROP 2 LAST CDS_LIB standard
J 0
(175 925);
DISPLAY INVISIBLE (175 925);
FORCEPROP 1 LAST BODY_TYPE PLUMBING
J 0
(175 975);
DISPLAY 0.872340 (175 975);
PAINT GREEN (175 975);
DISPLAY INVISIBLE (175 975);
FORCEPROP 1 LAST HDL_TAP TRUE
J 0
(500 800);
DISPLAY 0.872340 (500 800);
DISPLAY INVISIBLE (500 800);
FORCEPROP 1 LAST PATH I88
J 0
(173 925);
DISPLAY 0.872340 (173 925);
PAINT GREEN (173 925);
DISPLAY INVISIBLE (173 925);
FORCEADD TAP..1
(175 1125);
FORCEPROP 3 LASTPIN (125 1125) SIG_NAME P5E_CPU0_PE0_TX_C_DP<4>
J 0
(135 1135);
DISPLAY 0.659574 (135 1135);
PAINT MONO (135 1135);
DISPLAY INVISIBLE (135 1135);
FORCEPROP 1 LASTPIN (125 1125) BN 4
J 0
(113 1133);
DISPLAY 0.680851 (113 1133);
PAINT GREEN (113 1133);
FORCEPROP 2 LAST CDS_LIB standard
J 0
(175 1125);
DISPLAY INVISIBLE (175 1125);
FORCEPROP 1 LAST BODY_TYPE PLUMBING
J 0
(175 1175);
DISPLAY 0.872340 (175 1175);
PAINT GREEN (175 1175);
DISPLAY INVISIBLE (175 1175);
FORCEPROP 1 LAST HDL_TAP TRUE
J 0
(500 1000);
DISPLAY 0.872340 (500 1000);
DISPLAY INVISIBLE (500 1000);
FORCEPROP 1 LAST PATH I89
J 0
(173 1125);
DISPLAY 0.872340 (173 1125);
PAINT GREEN (173 1125);
DISPLAY INVISIBLE (173 1125);
FORCEADD TAP..1
R 2
(-1550 725);
FORCEPROP 3 LASTPIN (-1500 725) SIG_NAME P5E_CPU0_PE0_TX_DP<2>
J 0
(-1490 735);
DISPLAY 0.659574 (-1490 735);
PAINT MONO (-1490 735);
DISPLAY INVISIBLE (-1490 735);
FORCEPROP 1 LASTPIN (-1500 725) BN 2
J 2
(-1488 733);
DISPLAY 0.680851 (-1488 733);
PAINT GREEN (-1488 733);
FORCEPROP 2 LAST CDS_LIB standard
J 0
(-1550 725);
DISPLAY INVISIBLE (-1550 725);
FORCEPROP 1 LAST BODY_TYPE PLUMBING
J 2
(-1550 775);
DISPLAY 0.872340 (-1550 775);
PAINT GREEN (-1550 775);
DISPLAY INVISIBLE (-1550 775);
FORCEPROP 1 LAST HDL_TAP TRUE
J 2
(-1875 600);
DISPLAY 0.872340 (-1875 600);
DISPLAY INVISIBLE (-1875 600);
FORCEPROP 1 LAST PATH I9
J 2
(-1548 725);
DISPLAY 0.872340 (-1548 725);
PAINT GREEN (-1548 725);
DISPLAY INVISIBLE (-1548 725);
FORCEADD TAP..1
(175 1325);
FORCEPROP 3 LASTPIN (125 1325) SIG_NAME P5E_CPU0_PE0_TX_C_DP<5>
J 0
(135 1335);
DISPLAY 0.659574 (135 1335);
PAINT MONO (135 1335);
DISPLAY INVISIBLE (135 1335);
FORCEPROP 1 LASTPIN (125 1325) BN 5
J 0
(113 1333);
DISPLAY 0.680851 (113 1333);
PAINT GREEN (113 1333);
FORCEPROP 2 LAST CDS_LIB standard
J 0
(175 1325);
DISPLAY INVISIBLE (175 1325);
FORCEPROP 1 LAST BODY_TYPE PLUMBING
J 0
(175 1375);
DISPLAY 0.872340 (175 1375);
PAINT GREEN (175 1375);
DISPLAY INVISIBLE (175 1375);
FORCEPROP 1 LAST HDL_TAP TRUE
J 0
(500 1200);
DISPLAY 0.872340 (500 1200);
DISPLAY INVISIBLE (500 1200);
FORCEPROP 1 LAST PATH I90
J 0
(173 1325);
DISPLAY 0.872340 (173 1325);
PAINT GREEN (173 1325);
DISPLAY INVISIBLE (173 1325);
FORCEADD TAP..1
(175 1525);
FORCEPROP 3 LASTPIN (125 1525) SIG_NAME P5E_CPU0_PE0_TX_C_DP<6>
J 0
(135 1535);
DISPLAY 0.659574 (135 1535);
PAINT MONO (135 1535);
DISPLAY INVISIBLE (135 1535);
FORCEPROP 1 LASTPIN (125 1525) BN 6
J 0
(113 1533);
DISPLAY 0.680851 (113 1533);
PAINT GREEN (113 1533);
FORCEPROP 2 LAST CDS_LIB standard
J 0
(175 1525);
DISPLAY INVISIBLE (175 1525);
FORCEPROP 1 LAST BODY_TYPE PLUMBING
J 0
(175 1575);
DISPLAY 0.872340 (175 1575);
PAINT GREEN (175 1575);
DISPLAY INVISIBLE (175 1575);
FORCEPROP 1 LAST HDL_TAP TRUE
J 0
(500 1400);
DISPLAY 0.872340 (500 1400);
DISPLAY INVISIBLE (500 1400);
FORCEPROP 1 LAST PATH I91
J 0
(173 1525);
DISPLAY 0.872340 (173 1525);
PAINT GREEN (173 1525);
DISPLAY INVISIBLE (173 1525);
FORCEADD TAP..1
(175 1725);
FORCEPROP 3 LASTPIN (125 1725) SIG_NAME P5E_CPU0_PE0_TX_C_DP<7>
J 0
(135 1735);
DISPLAY 0.659574 (135 1735);
PAINT MONO (135 1735);
DISPLAY INVISIBLE (135 1735);
FORCEPROP 1 LASTPIN (125 1725) BN 7
J 0
(113 1733);
DISPLAY 0.680851 (113 1733);
PAINT GREEN (113 1733);
FORCEPROP 2 LAST CDS_LIB standard
J 0
(175 1725);
DISPLAY INVISIBLE (175 1725);
FORCEPROP 1 LAST BODY_TYPE PLUMBING
J 0
(175 1775);
DISPLAY 0.872340 (175 1775);
PAINT GREEN (175 1775);
DISPLAY INVISIBLE (175 1775);
FORCEPROP 1 LAST HDL_TAP TRUE
J 0
(500 1600);
DISPLAY 0.872340 (500 1600);
DISPLAY INVISIBLE (500 1600);
FORCEPROP 1 LAST PATH I92
J 0
(173 1725);
DISPLAY 0.872340 (173 1725);
PAINT GREEN (173 1725);
DISPLAY INVISIBLE (173 1725);
FORCEADD OFFPAGE..2
(1175 1750);
FORCEPROP 2 LAST $XR0 138 
J 0
(1364 1750);
DISPLAY 0.638298 (1364 1750);
PAINT MONO (1364 1750);
FORCEPROP 2 LAST CDS_LIB standard
J 0
(1175 1750);
DISPLAY INVISIBLE (1175 1750);
FORCEPROP 1 LAST OFFPAGE TRUE
J 0
(1500 1625);
DISPLAY 0.872340 (1500 1625);
DISPLAY INVISIBLE (1500 1625);
FORCEPROP 1 LAST COMMENT_BODY TRUE
J 0
(1130 1655);
DISPLAY 0.872340 (1130 1655);
PAINT GREEN (1130 1655);
DISPLAY INVISIBLE (1130 1655);
FORCEPROP 2 LAST PATH I93
J 0
(1375 1800);
DISPLAY 1.021277 (1375 1800);
DISPLAY INVISIBLE (1375 1800);
FORCEADD OFFPAGE..2
(1175 1800);
FORCEPROP 2 LAST $XR0 138 
J 0
(1364 1800);
DISPLAY 0.638298 (1364 1800);
PAINT MONO (1364 1800);
FORCEPROP 2 LAST CDS_LIB standard
J 0
(1175 1800);
DISPLAY INVISIBLE (1175 1800);
FORCEPROP 1 LAST OFFPAGE TRUE
J 0
(1500 1675);
DISPLAY 0.872340 (1500 1675);
DISPLAY INVISIBLE (1500 1675);
FORCEPROP 1 LAST COMMENT_BODY TRUE
J 0
(1130 1705);
DISPLAY 0.872340 (1130 1705);
PAINT GREEN (1130 1705);
DISPLAY INVISIBLE (1130 1705);
FORCEPROP 2 LAST PATH I94
J 0
(1375 1850);
DISPLAY 1.021277 (1375 1850);
DISPLAY INVISIBLE (1375 1850);
FORCEADD OFFPAGE..1
(2050 1750);
FORCEPROP 2 LAST $XR0 30 
J 0
(1829 1750);
DISPLAY 0.638298 (1829 1750);
PAINT MONO (1829 1750);
FORCEPROP 2 LAST CDS_LIB standard
J 0
(2050 1750);
DISPLAY INVISIBLE (2050 1750);
FORCEPROP 1 LAST OFFPAGE TRUE
J 0
(2375 1625);
DISPLAY 0.872340 (2375 1625);
DISPLAY INVISIBLE (2375 1625);
FORCEPROP 1 LAST COMMENT_BODY TRUE
J 0
(2175 1650);
DISPLAY 0.872340 (2175 1650);
PAINT GREEN (2175 1650);
DISPLAY INVISIBLE (2175 1650);
FORCEPROP 2 LAST PATH I95
J 0
(1800 1800);
DISPLAY 1.021277 (1800 1800);
DISPLAY INVISIBLE (1800 1800);
FORCEADD OFFPAGE..1
(2050 1800);
FORCEPROP 2 LAST $XR0 30 
J 0
(1829 1800);
DISPLAY 0.638298 (1829 1800);
PAINT MONO (1829 1800);
FORCEPROP 2 LAST CDS_LIB standard
J 0
(2050 1800);
DISPLAY INVISIBLE (2050 1800);
FORCEPROP 1 LAST OFFPAGE TRUE
J 0
(2375 1675);
DISPLAY 0.872340 (2375 1675);
DISPLAY INVISIBLE (2375 1675);
FORCEPROP 1 LAST COMMENT_BODY TRUE
J 0
(2175 1700);
DISPLAY 0.872340 (2175 1700);
PAINT GREEN (2175 1700);
DISPLAY INVISIBLE (2175 1700);
FORCEPROP 2 LAST PATH I96
J 0
(1800 1850);
DISPLAY 1.021277 (1800 1850);
DISPLAY INVISIBLE (1800 1850);
FORCEADD TAP..1
(175 2300);
FORCEPROP 3 LASTPIN (125 2300) SIG_NAME P5E_CPU0_PE0_TX_C_DP<8>
J 0
(135 2310);
DISPLAY 0.659574 (135 2310);
PAINT MONO (135 2310);
DISPLAY INVISIBLE (135 2310);
FORCEPROP 1 LASTPIN (125 2300) BN 8
J 0
(113 2308);
DISPLAY 0.680851 (113 2308);
PAINT GREEN (113 2308);
FORCEPROP 2 LAST CDS_LIB standard
J 0
(175 2300);
DISPLAY INVISIBLE (175 2300);
FORCEPROP 1 LAST BODY_TYPE PLUMBING
J 0
(175 2350);
DISPLAY 0.872340 (175 2350);
PAINT GREEN (175 2350);
DISPLAY INVISIBLE (175 2350);
FORCEPROP 1 LAST HDL_TAP TRUE
J 0
(500 2175);
DISPLAY 0.872340 (500 2175);
DISPLAY INVISIBLE (500 2175);
FORCEPROP 1 LAST PATH I97
J 0
(173 2300);
DISPLAY 0.872340 (173 2300);
PAINT GREEN (173 2300);
DISPLAY INVISIBLE (173 2300);
FORCEADD TAP..1
(175 2500);
FORCEPROP 3 LASTPIN (125 2500) SIG_NAME P5E_CPU0_PE0_TX_C_DP<9>
J 0
(135 2510);
DISPLAY 0.659574 (135 2510);
PAINT MONO (135 2510);
DISPLAY INVISIBLE (135 2510);
FORCEPROP 1 LASTPIN (125 2500) BN 9
J 0
(113 2508);
DISPLAY 0.680851 (113 2508);
PAINT GREEN (113 2508);
FORCEPROP 2 LAST CDS_LIB standard
J 0
(175 2500);
DISPLAY INVISIBLE (175 2500);
FORCEPROP 1 LAST BODY_TYPE PLUMBING
J 0
(175 2550);
DISPLAY 0.872340 (175 2550);
PAINT GREEN (175 2550);
DISPLAY INVISIBLE (175 2550);
FORCEPROP 1 LAST HDL_TAP TRUE
J 0
(500 2375);
DISPLAY 0.872340 (500 2375);
DISPLAY INVISIBLE (500 2375);
FORCEPROP 1 LAST PATH I98
J 0
(173 2500);
DISPLAY 0.872340 (173 2500);
PAINT GREEN (173 2500);
DISPLAY INVISIBLE (173 2500);
FORCEADD TAP..1
(175 2900);
FORCEPROP 3 LASTPIN (125 2900) SIG_NAME P5E_CPU0_PE0_TX_C_DP<11>
J 0
(135 2910);
DISPLAY 0.659574 (135 2910);
PAINT MONO (135 2910);
DISPLAY INVISIBLE (135 2910);
FORCEPROP 1 LASTPIN (125 2900) BN 11
J 0
(113 2908);
DISPLAY 0.680851 (113 2908);
PAINT GREEN (113 2908);
FORCEPROP 2 LAST CDS_LIB standard
J 0
(175 2900);
DISPLAY INVISIBLE (175 2900);
FORCEPROP 1 LAST BODY_TYPE PLUMBING
J 0
(175 2950);
DISPLAY 0.872340 (175 2950);
PAINT GREEN (175 2950);
DISPLAY INVISIBLE (175 2950);
FORCEPROP 1 LAST HDL_TAP TRUE
J 0
(500 2775);
DISPLAY 0.872340 (500 2775);
DISPLAY INVISIBLE (500 2775);
FORCEPROP 1 LAST PATH I99
J 0
(173 2900);
DISPLAY 0.872340 (173 2900);
PAINT GREEN (173 2900);
DISPLAY INVISIBLE (173 2900);
FORCEADD QUANTA_TITLE_BLOCK_C..1
(6300 -1650);
FORCEPROP 0 LAST CDS_CON_LAST_MODIFIED Fri Aug 25 14:02:44 2023
J 0
(4415 -1635);
DISPLAY INVISIBLE (4415 -1635);
FORCEPROP 2 LAST CUSTOM_TXT_CDS <XR_PAGE_TITLE>
J 0
(-1590 3600);
DISPLAY 0.638298 (-1590 3600);
PAINT PINK (-1590 3600);
DISPLAY INVISIBLE (-1590 3600);
FORCEPROP 2 LAST CUSTOM_TXT_CDS <CON_PAGE_NUM> OF <CON_TOTAL_PAGES>
J 0
(5854 -1632);
DISPLAY 0.978723 (5854 -1632);
FORCEPROP 2 LAST CUSTOM_TXT_CDS <Q_REV>
J 0
(6116 -1547);
DISPLAY 1.212766 (6116 -1547);
FORCEPROP 2 LAST CUSTOM_TXT_CDS <Q_PROJ>
J 0
(3918 -1548);
DISPLAY 1.212766 (3918 -1548);
FORCEPROP 2 LAST CUSTOM_TXT_CDS <Q_NUMBER>
J 0
(4897 -1547);
DISPLAY 1.212766 (4897 -1547);
FORCEPROP 2 LAST CUSTOM_TXT_CDS <CON_LAST_MODIFIED>
J 0
(4415 -1635);
DISPLAY 0.978723 (4415 -1635);
FORCEPROP 1 LAST CUSTOM_TXT_CDS <NAME_2>
J 0
(3125 -1600);
FORCEPROP 1 LAST CUSTOM_TXT_CDS <NAME_1>
J 0
(3125 -1475);
FORCEPROP 1 LAST Q_TITLE PCIE AC-COUPLE CAPS 1/5
J 0
(-3066 -1624);
DISPLAY 2.446809 (-3066 -1624);
PAINT GREEN (-3066 -1624);
FORCEPROP 1 LAST Q_DEPT 
J 1
(2537 -1601);
DISPLAY 1.957447 (2537 -1601);
PAINT GREEN (2537 -1601);
FORCEPROP 2 LAST CDS_XR_PAGE_TITLE CR-173 : @S9S_MB_2U_LIB.S9S_MB_2U(SCH_1):PAGE173
J 0
(-1590 3600);
DISPLAY 0.638298 (-1590 3600);
PAINT PINK (-1590 3600);
DISPLAY INVISIBLE (-1590 3600);
FORCEPROP 2 LAST CDS_LIB pure_quanta
J 0
(6300 -1650);
DISPLAY INVISIBLE (6300 -1650);
FORCEPROP 1 LAST CDS_LMAN_SYM_OUTLINE -9475,6775,100,-125
J 0
(6300 -1650);
DISPLAY 0.468085 (6300 -1650);
PAINT GREEN (6300 -1650);
DISPLAY INVISIBLE (6300 -1650);
FORCEPROP 1 LAST COMMENT_BODY TRUE
J 0
(6312 -1663);
DISPLAY 0.978723 (6312 -1663);
PAINT GREEN (6312 -1663);
DISPLAY INVISIBLE (6312 -1663);
FORCEPROP 2 LAST PAGE_BORDER TRUE
J 0
(-1590 3600);
DISPLAY 0.638298 (-1590 3600);
PAINT PINK (-1590 3600);
DISPLAY INVISIBLE (-1590 3600);
WIRE 17 -1 (-1600 350)(-1600 550);
WIRE 17 -1 (-1600 550)(-1600 750);
WIRE 17 -1 (-1600 750)(-1600 950);
WIRE 17 -1 (-1600 950)(-1600 1150);
WIRE 17 -1 (-1600 1150)(-1600 1350);
WIRE 17 -1 (-1600 1350)(-1600 1550);
WIRE 17 -1 (-1600 1550)(-1600 1750);
WIRE 17 -1 (-2450 1750)(-1600 1750);
FORCEPROP 2 LAST SIG_NAME P5E_CPU0_PE0_TX_DP<7:0>
J 0
(-2435 1760);
DISPLAY 0.680851 (-2435 1760);
PAINT WHITE (-2435 1760);
WIRE 17 -1 (-1350 1800)(-1350 1600);
WIRE 17 -1 (-2450 1800)(-1350 1800);
FORCEPROP 2 LAST SIG_NAME P5E_CPU0_PE0_TX_DN<7:0>
J 0
(-2435 1810);
DISPLAY 0.680851 (-2435 1810);
PAINT WHITE (-2435 1810);
WIRE 17 -1 (-1350 800)(-1350 600);
WIRE 17 -1 (-1350 1000)(-1350 800);
WIRE 17 -1 (-1350 600)(-1350 400);
WIRE 17 -1 (-1350 1000)(-1350 1200);
WIRE 17 -1 (-1350 1400)(-1350 1200);
WIRE 17 -1 (-1350 1600)(-1350 1400);
WIRE 17 -1 (-1600 2725)(-1600 2925);
WIRE 17 -1 (-1600 2525)(-1600 2725);
WIRE 17 -1 (-1600 2925)(-1600 3125);
WIRE 17 -1 (-1600 3125)(-1600 3325);
WIRE 17 -1 (-1600 2325)(-1600 2525);
WIRE 17 -1 (-1600 3325)(-1600 3525);
WIRE 17 -1 (-1600 3525)(-1600 3725);
WIRE 17 -1 (-2450 3725)(-1600 3725);
FORCEPROP 2 LAST SIG_NAME P5E_CPU0_PE0_TX_DP<15:8>
J 0
(-2435 3735);
DISPLAY 0.680851 (-2435 3735);
PAINT WHITE (-2435 3735);
WIRE 17 -1 (-1350 3775)(-1350 3575);
WIRE 17 -1 (-2450 3775)(-1350 3775);
FORCEPROP 2 LAST SIG_NAME P5E_CPU0_PE0_TX_DN<15:8>
J 0
(-2435 3785);
DISPLAY 0.680851 (-2435 3785);
PAINT WHITE (-2435 3785);
WIRE 17 -1 (-1350 2975)(-1350 2775);
WIRE 17 -1 (-1350 2975)(-1350 3175);
WIRE 17 -1 (-1350 2775)(-1350 2575);
WIRE 17 -1 (-1350 2575)(-1350 2375);
WIRE 17 -1 (-1350 3375)(-1350 3175);
WIRE 17 -1 (-1350 3575)(-1350 3375);
WIRE 17 -1 (225 2925)(225 3125);
WIRE 17 -1 (225 2925)(225 2725);
WIRE 17 -1 (225 3325)(225 3125);
WIRE 17 -1 (225 3525)(225 3325);
WIRE 17 -1 (225 2725)(225 2525);
WIRE 17 -1 (225 2525)(225 2325);
WIRE 17 -1 (225 3725)(225 3525);
WIRE 17 -1 (225 3725)(1125 3725);
FORCEPROP 2 LAST SIG_NAME P5E_CPU0_PE0_TX_C_DP<15:8>
J 0
(290 3735);
DISPLAY 0.680851 (290 3735);
PAINT WHITE (290 3735);
WIRE 17 -1 (225 1750)(1125 1750);
FORCEPROP 2 LAST SIG_NAME P5E_CPU0_PE0_TX_C_DP<7:0>
J 0
(290 1760);
DISPLAY 0.680851 (290 1760);
PAINT WHITE (290 1760);
WIRE 17 -1 (25 1800)(1125 1800);
FORCEPROP 2 LAST SIG_NAME P5E_CPU0_PE0_TX_C_DN<7:0>
J 0
(290 1810);
DISPLAY 0.680851 (290 1810);
PAINT WHITE (290 1810);
WIRE 17 -1 (25 2575)(25 2375);
WIRE 17 -1 (25 2775)(25 2575);
WIRE 17 -1 (25 2975)(25 2775);
WIRE 17 -1 (25 2975)(25 3175);
WIRE 17 -1 (25 3375)(25 3175);
WIRE 17 -1 (25 3575)(25 3375);
WIRE 17 -1 (25 3775)(25 3575);
WIRE 17 -1 (25 3775)(1125 3775);
FORCEPROP 2 LAST SIG_NAME P5E_CPU0_PE0_TX_C_DN<15:8>
J 0
(290 3785);
DISPLAY 0.680851 (290 3785);
PAINT WHITE (290 3785);
WIRE 17 -1 (25 1800)(25 1600);
WIRE 17 -1 (225 1750)(225 1550);
WIRE 17 -1 (25 1600)(25 1400);
WIRE 17 -1 (25 1400)(25 1200);
WIRE 17 -1 (25 1000)(25 1200);
WIRE 17 -1 (225 1550)(225 1350);
WIRE 17 -1 (225 1350)(225 1150);
WIRE 17 -1 (225 950)(225 1150);
WIRE 17 -1 (25 1000)(25 800);
WIRE 17 -1 (25 800)(25 600);
WIRE 17 -1 (25 600)(25 400);
WIRE 17 -1 (225 750)(225 550);
WIRE 17 -1 (225 950)(225 750);
WIRE 17 -1 (225 550)(225 350);
WIRE 17 -1 (3200 600)(3200 400);
WIRE 17 -1 (3200 800)(3200 600);
WIRE 17 -1 (3200 1000)(3200 800);
WIRE 17 -1 (3200 1000)(3200 1200);
WIRE 17 -1 (3200 1400)(3200 1200);
WIRE 17 -1 (3200 1600)(3200 1400);
WIRE 17 -1 (3200 1800)(3200 1600);
WIRE 17 -1 (2100 1800)(3200 1800);
FORCEPROP 2 LAST SIG_NAME P5E_CPU0_PE2_TX_DN<7:0>
J 0
(2140 1810);
DISPLAY 0.680851 (2140 1810);
PAINT WHITE (2140 1810);
WIRE 17 -1 (2950 550)(2950 750);
WIRE 17 -1 (2950 350)(2950 550);
WIRE 17 -1 (2950 750)(2950 950);
WIRE 17 -1 (2950 950)(2950 1150);
WIRE 17 -1 (2950 1150)(2950 1350);
WIRE 17 -1 (2950 1350)(2950 1550);
WIRE 17 -1 (2950 1550)(2950 1750);
WIRE 17 -1 (2100 1750)(2950 1750);
FORCEPROP 2 LAST SIG_NAME P5E_CPU0_PE2_TX_DP<7:0>
J 0
(2140 1760);
DISPLAY 0.680851 (2140 1760);
PAINT WHITE (2140 1760);
WIRE 17 -1 (2950 2725)(2950 2925);
WIRE 17 -1 (2950 2525)(2950 2725);
WIRE 17 -1 (2950 2925)(2950 3125);
WIRE 17 -1 (2950 3125)(2950 3325);
WIRE 17 -1 (2950 2325)(2950 2525);
WIRE 17 -1 (2950 3325)(2950 3525);
WIRE 17 -1 (2950 3525)(2950 3725);
WIRE 17 -1 (2100 3725)(2950 3725);
FORCEPROP 2 LAST SIG_NAME P5E_CPU0_PE2_TX_DP<15:8>
J 0
(2140 3735);
DISPLAY 0.680851 (2140 3735);
PAINT WHITE (2140 3735);
WIRE 17 -1 (3200 2575)(3200 2375);
WIRE 17 -1 (3200 2775)(3200 2575);
WIRE 17 -1 (3200 2975)(3200 2775);
WIRE 17 -1 (3200 2975)(3200 3175);
WIRE 17 -1 (3200 3375)(3200 3175);
WIRE 17 -1 (3200 3575)(3200 3375);
WIRE 17 -1 (3200 3775)(3200 3575);
WIRE 17 -1 (2100 3775)(3200 3775);
FORCEPROP 2 LAST SIG_NAME P5E_CPU0_PE2_TX_DN<15:8>
J 0
(2140 3785);
DISPLAY 0.680851 (2140 3785);
PAINT WHITE (2140 3785);
WIRE 17 -1 (4575 600)(4575 400);
WIRE 17 -1 (4575 800)(4575 600);
WIRE 17 -1 (4575 1000)(4575 800);
WIRE 17 -1 (4575 1000)(4575 1200);
WIRE 17 -1 (4575 1400)(4575 1200);
WIRE 17 -1 (4575 1600)(4575 1400);
WIRE 17 -1 (4575 1800)(4575 1600);
WIRE 17 -1 (4575 1800)(5675 1800);
FORCEPROP 2 LAST SIG_NAME P5E_CPU0_PE2_TX_C_DN<7:0>
J 0
(4815 1810);
DISPLAY 0.680851 (4815 1810);
PAINT WHITE (4815 1810);
WIRE 17 -1 (4775 950)(4775 1150);
WIRE 17 -1 (4775 950)(4775 750);
WIRE 17 -1 (4775 1350)(4775 1150);
WIRE 17 -1 (4775 1550)(4775 1350);
WIRE 17 -1 (4775 750)(4775 550);
WIRE 17 -1 (4775 550)(4775 350);
WIRE 17 -1 (4775 1750)(4775 1550);
WIRE 17 -1 (4775 1750)(5675 1750);
FORCEPROP 2 LAST SIG_NAME P5E_CPU0_PE2_TX_C_DP<7:0>
J 0
(4815 1760);
DISPLAY 0.680851 (4815 1760);
PAINT WHITE (4815 1760);
WIRE 17 -1 (4575 2775)(4575 2575);
WIRE 17 -1 (4575 2975)(4575 2775);
WIRE 17 -1 (4575 2575)(4575 2375);
WIRE 17 -1 (4575 2975)(4575 3175);
WIRE 17 -1 (4575 3375)(4575 3175);
WIRE 17 -1 (4575 3575)(4575 3375);
WIRE 17 -1 (4575 3775)(4575 3575);
WIRE 17 -1 (4575 3775)(5675 3775);
FORCEPROP 2 LAST SIG_NAME P5E_CPU0_PE2_TX_C_DN<15:8>
J 0
(4815 3785);
DISPLAY 0.680851 (4815 3785);
PAINT WHITE (4815 3785);
WIRE 17 -1 (4775 2925)(4775 3125);
WIRE 17 -1 (4775 2925)(4775 2725);
WIRE 17 -1 (4775 3325)(4775 3125);
WIRE 17 -1 (4775 3525)(4775 3325);
WIRE 17 -1 (4775 2725)(4775 2525);
WIRE 17 -1 (4775 2525)(4775 2325);
WIRE 17 -1 (4775 3725)(4775 3525);
WIRE 17 -1 (4775 3725)(5675 3725);
FORCEPROP 2 LAST SIG_NAME P5E_CPU0_PE2_TX_C_DP<15:8>
J 0
(4815 3735);
DISPLAY 0.680851 (4815 3735);
PAINT WHITE (4815 3735);
WIRE 16 -1 (-650 2300)(-1500 2300);
WIRE 16 -1 (3900 325)(3050 325);
WIRE 16 -1 (4050 525)(4675 525);
WIRE 16 -1 (4050 725)(4675 725);
WIRE 16 -1 (4050 775)(4475 775);
WIRE 16 -1 (3900 1325)(3050 1325);
WIRE 16 -1 (3900 1375)(3300 1375);
WIRE 16 -1 (3900 1525)(3050 1525);
WIRE 16 -1 (3900 1575)(3300 1575);
WIRE 16 -1 (3900 1725)(3050 1725);
WIRE 16 -1 (3900 1775)(3300 1775);
WIRE 16 -1 (4050 925)(4675 925);
WIRE 16 -1 (4050 575)(4475 575);
WIRE 16 -1 (4050 325)(4675 325);
WIRE 16 -1 (4050 3700)(4675 3700);
WIRE 16 -1 (4050 3500)(4675 3500);
WIRE 16 -1 (4050 3300)(4675 3300);
WIRE 16 -1 (4050 3750)(4475 3750);
WIRE 16 -1 (4050 3550)(4475 3550);
WIRE 16 -1 (4050 3350)(4475 3350);
WIRE 16 -1 (4050 3100)(4675 3100);
WIRE 16 -1 (4050 2300)(4675 2300);
WIRE 16 -1 (4050 2500)(4675 2500);
WIRE 16 -1 (4050 2700)(4675 2700);
WIRE 16 -1 (4050 2900)(4675 2900);
WIRE 16 -1 (4050 2950)(4475 2950);
WIRE 16 -1 (4050 3150)(4475 3150);
WIRE 16 -1 (4050 2750)(4475 2750);
WIRE 16 -1 (4050 2350)(4475 2350);
WIRE 16 -1 (4050 2550)(4475 2550);
WIRE 16 -1 (4050 1325)(4675 1325);
WIRE 16 -1 (4050 1725)(4675 1725);
WIRE 16 -1 (4050 1525)(4675 1525);
WIRE 16 -1 (4050 1775)(4475 1775);
WIRE 16 -1 (4050 1175)(4475 1175);
WIRE 16 -1 (4050 1375)(4475 1375);
WIRE 16 -1 (4050 1575)(4475 1575);
WIRE 16 -1 (4050 1125)(4675 1125);
WIRE 16 -1 (4050 975)(4475 975);
WIRE 16 -1 (4050 375)(4475 375);
WIRE 16 -1 (3900 3700)(3050 3700);
WIRE 16 -1 (3900 3300)(3050 3300);
WIRE 16 -1 (3900 3750)(3300 3750);
WIRE 16 -1 (3900 3350)(3300 3350);
WIRE 16 -1 (3900 3550)(3300 3550);
WIRE 16 -1 (3900 3500)(3050 3500);
WIRE 16 -1 (3900 2700)(3050 2700);
WIRE 16 -1 (3900 2750)(3300 2750);
WIRE 16 -1 (3900 2550)(3300 2550);
WIRE 16 -1 (3900 3150)(3300 3150);
WIRE 16 -1 (3900 3100)(3050 3100);
WIRE 16 -1 (3900 2500)(3050 2500);
WIRE 16 -1 (3900 2950)(3300 2950);
WIRE 16 -1 (3900 2300)(3050 2300);
WIRE 16 -1 (3900 2350)(3300 2350);
WIRE 16 -1 (3900 2900)(3050 2900);
WIRE 16 -1 (3900 1175)(3300 1175);
WIRE 16 -1 (3900 775)(3300 775);
WIRE 16 -1 (3900 575)(3300 575);
WIRE 16 -1 (3900 925)(3050 925);
WIRE 16 -1 (3900 975)(3300 975);
WIRE 16 -1 (3900 1125)(3050 1125);
WIRE 16 -1 (3900 525)(3050 525);
WIRE 16 -1 (3900 725)(3050 725);
WIRE 16 -1 (3900 375)(3300 375);
WIRE 16 -1 (-500 2700)(125 2700);
WIRE 16 -1 (-500 2750)(-75 2750);
WIRE 16 -1 (-500 925)(125 925);
WIRE 16 -1 (-500 1125)(125 1125);
WIRE 16 -1 (-500 725)(125 725);
WIRE 16 -1 (-500 975)(-75 975);
WIRE 16 -1 (-500 325)(125 325);
WIRE 16 -1 (-500 375)(-75 375);
WIRE 16 -1 (-500 1175)(-75 1175);
WIRE 16 -1 (-500 575)(-75 575);
WIRE 16 -1 (-500 525)(125 525);
WIRE 16 -1 (-500 775)(-75 775);
WIRE 16 -1 (-500 1325)(125 1325);
WIRE 16 -1 (-500 1375)(-75 1375);
WIRE 16 -1 (-500 1525)(125 1525);
WIRE 16 -1 (-500 1575)(-75 1575);
WIRE 16 -1 (-500 2300)(125 2300);
WIRE 16 -1 (-500 3550)(-75 3550);
WIRE 16 -1 (-500 2550)(-75 2550);
WIRE 16 -1 (-500 3100)(125 3100);
WIRE 16 -1 (-500 3150)(-75 3150);
WIRE 16 -1 (-500 3300)(125 3300);
WIRE 16 -1 (-500 2950)(-75 2950);
WIRE 16 -1 (-500 3750)(-75 3750);
WIRE 16 -1 (-500 3700)(125 3700);
WIRE 16 -1 (-500 3500)(125 3500);
WIRE 16 -1 (-500 3350)(-75 3350);
WIRE 16 -1 (-500 2500)(125 2500);
WIRE 16 -1 (-500 2350)(-75 2350);
WIRE 16 -1 (-500 1775)(-75 1775);
WIRE 16 -1 (-500 1725)(125 1725);
WIRE 16 -1 (-500 2900)(125 2900);
WIRE 16 -1 (-650 2700)(-1500 2700);
WIRE 16 -1 (-650 3300)(-1500 3300);
WIRE 16 -1 (-650 2550)(-1250 2550);
WIRE 16 -1 (-650 2950)(-1250 2950);
WIRE 16 -1 (-650 3150)(-1250 3150);
WIRE 16 -1 (-650 3350)(-1250 3350);
WIRE 16 -1 (-650 3100)(-1500 3100);
WIRE 16 -1 (-650 3750)(-1250 3750);
WIRE 16 -1 (-650 3700)(-1500 3700);
WIRE 16 -1 (-650 2500)(-1500 2500);
WIRE 16 -1 (-650 2350)(-1250 2350);
WIRE 16 -1 (-650 2750)(-1250 2750);
WIRE 16 -1 (-650 3550)(-1250 3550);
WIRE 16 -1 (-650 3500)(-1500 3500);
WIRE 16 -1 (-650 2900)(-1500 2900);
WIRE 16 -1 (-650 1575)(-1250 1575);
WIRE 16 -1 (-650 1725)(-1500 1725);
WIRE 16 -1 (-650 725)(-1500 725);
WIRE 16 -1 (-650 925)(-1500 925);
WIRE 16 -1 (-650 1125)(-1500 1125);
WIRE 16 -1 (-650 1175)(-1250 1175);
WIRE 16 -1 (-650 375)(-1250 375);
WIRE 16 -1 (-650 775)(-1250 775);
WIRE 16 -1 (-650 975)(-1250 975);
WIRE 16 -1 (-650 1525)(-1500 1525);
WIRE 16 -1 (-650 1325)(-1500 1325);
WIRE 16 -1 (-650 1375)(-1250 1375);
WIRE 16 -1 (-650 575)(-1250 575);
WIRE 16 -1 (-650 525)(-1500 525);
WIRE 16 -1 (-650 1775)(-1250 1775);
WIRE 16 -1 (-650 325)(-1500 325);
FORCENOTE
20210527 MODIFY FOR GT
(2525 4425) 0;
DISPLAY LEFT (2525 4425);
DISPLAY 2.510638 (2525 4425);
PAINT PINK (2525 4425);
FORCENOTE
CPU0 PCIE0 TX
(-1900 -300) 0;
DISPLAY LEFT (-1900 -300);
DISPLAY 4.148936 (-1900 -300);
PAINT WHITE (-1900 -300);
FORCENOTE
CPU0 PCIE2 TX
(2700 -300) 0;
DISPLAY LEFT (2700 -300);
DISPLAY 4.148936 (2700 -300);
PAINT WHITE (2700 -300);
QUIT
